FILE_TYPE = MACRO_DRAWING;
SET COLOR_WIRE YELLOW;
SET COLOR_PROP ORANGE;
SET COLOR_DOT WHITE;
SET COLOR_ARC YELLOW;
SET COLOR_BODY GREEN;
SET COLOR_NOTE PURPLE;
SET PROP_DISPLAY VALUE;
SET PAGE_NUMBER P31;
FORCEADD GENOA_SP5..28
(-8600 3400);
FORCEPROP 1 LAST LOCATION U25
J 0
(-9000 6600);
DISPLAY 0.489362 (-9000 6600);
PAINT SKYBLUE (-9000 6600);
FORCEPROP 0 LAST $SEC 28
J 0
(-8975 6800);
DISPLAY 0.680851 (-8975 6800);
PAINT MONO (-8975 6800);
DISPLAY INVISIBLE (-8975 6800);
FORCEPROP 0 LAST CDS_SEC 28
J 0
(-9000 6700);
DISPLAY 1.021277 (-9000 6700);
DISPLAY INVISIBLE (-9000 6700);
FORCEPROP 0 LASTPIN (-9150 6350) $PN A3
J 2
(-9160 6360);
DISPLAY 0.489362 (-9160 6360);
PAINT MONO (-9160 6360);
FORCEPROP 0 LASTPIN (-9150 6300) $PN A9
J 2
(-9160 6310);
DISPLAY 0.489362 (-9160 6310);
PAINT MONO (-9160 6310);
FORCEPROP 0 LASTPIN (-9150 6250) $PN A15
J 2
(-9160 6260);
DISPLAY 0.489362 (-9160 6260);
PAINT MONO (-9160 6260);
FORCEPROP 0 LASTPIN (-9150 6200) $PN A21
J 2
(-9160 6210);
DISPLAY 0.489362 (-9160 6210);
PAINT MONO (-9160 6210);
FORCEPROP 0 LASTPIN (-9150 6150) $PN A27
J 2
(-9160 6160);
DISPLAY 0.489362 (-9160 6160);
PAINT MONO (-9160 6160);
FORCEPROP 0 LASTPIN (-9150 6100) $PN A43
J 2
(-9160 6110);
DISPLAY 0.489362 (-9160 6110);
PAINT MONO (-9160 6110);
FORCEPROP 0 LASTPIN (-9150 6050) $PN A44
J 2
(-9160 6060);
DISPLAY 0.489362 (-9160 6060);
PAINT MONO (-9160 6060);
FORCEPROP 0 LASTPIN (-9150 6000) $PN A47
J 2
(-9160 6010);
DISPLAY 0.489362 (-9160 6010);
PAINT MONO (-9160 6010);
FORCEPROP 0 LASTPIN (-9150 5950) $PN A49
J 2
(-9160 5960);
DISPLAY 0.489362 (-9160 5960);
PAINT MONO (-9160 5960);
FORCEPROP 0 LASTPIN (-9150 5900) $PN A53
J 2
(-9160 5910);
DISPLAY 0.489362 (-9160 5910);
PAINT MONO (-9160 5910);
FORCEPROP 0 LASTPIN (-9150 5850) $PN A61
J 2
(-9160 5860);
DISPLAY 0.489362 (-9160 5860);
PAINT MONO (-9160 5860);
FORCEPROP 0 LASTPIN (-9150 5800) $PN A67
J 2
(-9160 5810);
DISPLAY 0.489362 (-9160 5810);
PAINT MONO (-9160 5810);
FORCEPROP 0 LASTPIN (-9150 5750) $PN A72
J 2
(-9160 5760);
DISPLAY 0.489362 (-9160 5760);
PAINT MONO (-9160 5760);
FORCEPROP 0 LASTPIN (-9150 5700) $PN A73
J 2
(-9160 5710);
DISPLAY 0.489362 (-9160 5710);
PAINT MONO (-9160 5710);
FORCEPROP 0 LASTPIN (-9150 5650) $PN B7
J 2
(-9160 5660);
DISPLAY 0.489362 (-9160 5660);
PAINT MONO (-9160 5660);
FORCEPROP 0 LASTPIN (-9150 5600) $PN B8
J 2
(-9160 5610);
DISPLAY 0.489362 (-9160 5610);
PAINT MONO (-9160 5610);
FORCEPROP 0 LASTPIN (-9150 5550) $PN B10
J 2
(-9160 5560);
DISPLAY 0.489362 (-9160 5560);
PAINT MONO (-9160 5560);
FORCEPROP 0 LASTPIN (-9150 5500) $PN B11
J 2
(-9160 5510);
DISPLAY 0.489362 (-9160 5510);
PAINT MONO (-9160 5510);
FORCEPROP 0 LASTPIN (-9150 5450) $PN B13
J 2
(-9160 5460);
DISPLAY 0.489362 (-9160 5460);
PAINT MONO (-9160 5460);
FORCEPROP 0 LASTPIN (-9150 5400) $PN B18
J 2
(-9160 5410);
DISPLAY 0.489362 (-9160 5410);
PAINT MONO (-9160 5410);
FORCEPROP 0 LASTPIN (-9150 5350) $PN B24
J 2
(-9160 5360);
DISPLAY 0.489362 (-9160 5360);
PAINT MONO (-9160 5360);
FORCEPROP 0 LASTPIN (-9150 5300) $PN B27
J 2
(-9160 5310);
DISPLAY 0.489362 (-9160 5310);
PAINT MONO (-9160 5310);
FORCEPROP 0 LASTPIN (-9150 5250) $PN B30
J 2
(-9160 5260);
DISPLAY 0.489362 (-9160 5260);
PAINT MONO (-9160 5260);
FORCEPROP 0 LASTPIN (-9150 5200) $PN B33
J 2
(-9160 5210);
DISPLAY 0.489362 (-9160 5210);
PAINT MONO (-9160 5210);
FORCEPROP 0 LASTPIN (-9150 5150) $PN B37
J 2
(-9160 5160);
DISPLAY 0.489362 (-9160 5160);
PAINT MONO (-9160 5160);
FORCEPROP 0 LASTPIN (-9150 5100) $PN B39
J 2
(-9160 5110);
DISPLAY 0.489362 (-9160 5110);
PAINT MONO (-9160 5110);
FORCEPROP 0 LASTPIN (-9150 5050) $PN B43
J 2
(-9160 5060);
DISPLAY 0.489362 (-9160 5060);
PAINT MONO (-9160 5060);
FORCEPROP 0 LASTPIN (-9150 5000) $PN B46
J 2
(-9160 5010);
DISPLAY 0.489362 (-9160 5010);
PAINT MONO (-9160 5010);
FORCEPROP 0 LASTPIN (-9150 4950) $PN B49
J 2
(-9160 4960);
DISPLAY 0.489362 (-9160 4960);
PAINT MONO (-9160 4960);
FORCEPROP 0 LASTPIN (-9150 4900) $PN B52
J 2
(-9160 4910);
DISPLAY 0.489362 (-9160 4910);
PAINT MONO (-9160 4910);
FORCEPROP 0 LASTPIN (-9150 4850) $PN B55
J 2
(-9160 4860);
DISPLAY 0.489362 (-9160 4860);
PAINT MONO (-9160 4860);
FORCEPROP 0 LASTPIN (-9150 4800) $PN B59
J 2
(-9160 4810);
DISPLAY 0.489362 (-9160 4810);
PAINT MONO (-9160 4810);
FORCEPROP 0 LASTPIN (-9150 4750) $PN B62
J 2
(-9160 4760);
DISPLAY 0.489362 (-9160 4760);
PAINT MONO (-9160 4760);
FORCEPROP 0 LASTPIN (-9150 4700) $PN B65
J 2
(-9160 4710);
DISPLAY 0.489362 (-9160 4710);
PAINT MONO (-9160 4710);
FORCEPROP 0 LASTPIN (-9150 4650) $PN B68
J 2
(-9160 4660);
DISPLAY 0.489362 (-9160 4660);
PAINT MONO (-9160 4660);
FORCEPROP 0 LASTPIN (-9150 4600) $PN B70
J 2
(-9160 4610);
DISPLAY 0.489362 (-9160 4610);
PAINT MONO (-9160 4610);
FORCEPROP 0 LASTPIN (-9150 4550) $PN C1
J 2
(-9160 4560);
DISPLAY 0.489362 (-9160 4560);
PAINT MONO (-9160 4560);
FORCEPROP 0 LASTPIN (-9150 4500) $PN C5
J 2
(-9160 4510);
DISPLAY 0.489362 (-9160 4510);
PAINT MONO (-9160 4510);
FORCEPROP 0 LASTPIN (-9150 4450) $PN C8
J 2
(-9160 4460);
DISPLAY 0.489362 (-9160 4460);
PAINT MONO (-9160 4460);
FORCEPROP 0 LASTPIN (-9150 4400) $PN C10
J 2
(-9160 4410);
DISPLAY 0.489362 (-9160 4410);
PAINT MONO (-9160 4410);
FORCEPROP 0 LASTPIN (-9150 4350) $PN C11
J 2
(-9160 4360);
DISPLAY 0.489362 (-9160 4360);
PAINT MONO (-9160 4360);
FORCEPROP 0 LASTPIN (-9150 4300) $PN C13
J 2
(-9160 4310);
DISPLAY 0.489362 (-9160 4310);
PAINT MONO (-9160 4310);
FORCEPROP 0 LASTPIN (-9150 4250) $PN C15
J 2
(-9160 4260);
DISPLAY 0.489362 (-9160 4260);
PAINT MONO (-9160 4260);
FORCEPROP 0 LASTPIN (-9150 4200) $PN C21
J 2
(-9160 4210);
DISPLAY 0.489362 (-9160 4210);
PAINT MONO (-9160 4210);
FORCEPROP 0 LASTPIN (-9150 4150) $PN C24
J 2
(-9160 4160);
DISPLAY 0.489362 (-9160 4160);
PAINT MONO (-9160 4160);
FORCEPROP 0 LASTPIN (-9150 4100) $PN C27
J 2
(-9160 4110);
DISPLAY 0.489362 (-9160 4110);
PAINT MONO (-9160 4110);
FORCEPROP 0 LASTPIN (-9150 4050) $PN C30
J 2
(-9160 4060);
DISPLAY 0.489362 (-9160 4060);
PAINT MONO (-9160 4060);
FORCEPROP 0 LASTPIN (-9150 4000) $PN C36
J 2
(-9160 4010);
DISPLAY 0.489362 (-9160 4010);
PAINT MONO (-9160 4010);
FORCEPROP 0 LASTPIN (-9150 3950) $PN C40
J 2
(-9160 3960);
DISPLAY 0.489362 (-9160 3960);
PAINT MONO (-9160 3960);
FORCEPROP 0 LASTPIN (-9150 3900) $PN C43
J 2
(-9160 3910);
DISPLAY 0.489362 (-9160 3910);
PAINT MONO (-9160 3910);
FORCEPROP 0 LASTPIN (-9150 3850) $PN C46
J 2
(-9160 3860);
DISPLAY 0.489362 (-9160 3860);
PAINT MONO (-9160 3860);
FORCEPROP 0 LASTPIN (-9150 3800) $PN C49
J 2
(-9160 3810);
DISPLAY 0.489362 (-9160 3810);
PAINT MONO (-9160 3810);
FORCEPROP 0 LASTPIN (-9150 3750) $PN C52
J 2
(-9160 3760);
DISPLAY 0.489362 (-9160 3760);
PAINT MONO (-9160 3760);
FORCEPROP 0 LASTPIN (-9150 3700) $PN C55
J 2
(-9160 3710);
DISPLAY 0.489362 (-9160 3710);
PAINT MONO (-9160 3710);
FORCEPROP 0 LASTPIN (-9150 3650) $PN C56
J 2
(-9160 3660);
DISPLAY 0.489362 (-9160 3660);
PAINT MONO (-9160 3660);
FORCEPROP 0 LASTPIN (-9150 3600) $PN C57
J 2
(-9160 3610);
DISPLAY 0.489362 (-9160 3610);
PAINT MONO (-9160 3610);
FORCEPROP 0 LASTPIN (-9150 3550) $PN C61
J 2
(-9160 3560);
DISPLAY 0.489362 (-9160 3560);
PAINT MONO (-9160 3560);
FORCEPROP 0 LASTPIN (-9150 3500) $PN C64
J 2
(-9160 3510);
DISPLAY 0.489362 (-9160 3510);
PAINT MONO (-9160 3510);
FORCEPROP 0 LASTPIN (-9150 3450) $PN C67
J 2
(-9160 3460);
DISPLAY 0.489362 (-9160 3460);
PAINT MONO (-9160 3460);
FORCEPROP 0 LASTPIN (-9150 3400) $PN C69
J 2
(-9160 3410);
DISPLAY 0.489362 (-9160 3410);
PAINT MONO (-9160 3410);
FORCEPROP 0 LASTPIN (-9150 3350) $PN C71
J 2
(-9160 3360);
DISPLAY 0.489362 (-9160 3360);
PAINT MONO (-9160 3360);
FORCEPROP 0 LASTPIN (-9150 3300) $PN C73
J 2
(-9160 3310);
DISPLAY 0.489362 (-9160 3310);
PAINT MONO (-9160 3310);
FORCEPROP 0 LASTPIN (-9150 3250) $PN C75
J 2
(-9160 3260);
DISPLAY 0.489362 (-9160 3260);
PAINT MONO (-9160 3260);
FORCEPROP 0 LASTPIN (-9150 3200) $PN D2
J 2
(-9160 3210);
DISPLAY 0.489362 (-9160 3210);
PAINT MONO (-9160 3210);
FORCEPROP 0 LASTPIN (-9150 3150) $PN D3
J 2
(-9160 3160);
DISPLAY 0.489362 (-9160 3160);
PAINT MONO (-9160 3160);
FORCEPROP 0 LASTPIN (-9150 3100) $PN D5
J 2
(-9160 3110);
DISPLAY 0.489362 (-9160 3110);
PAINT MONO (-9160 3110);
FORCEPROP 0 LASTPIN (-9150 3050) $PN D6
J 2
(-9160 3060);
DISPLAY 0.489362 (-9160 3060);
PAINT MONO (-9160 3060);
FORCEPROP 0 LASTPIN (-9150 3000) $PN D9
J 2
(-9160 3010);
DISPLAY 0.489362 (-9160 3010);
PAINT MONO (-9160 3010);
FORCEPROP 0 LASTPIN (-9150 2950) $PN D10
J 2
(-9160 2960);
DISPLAY 0.489362 (-9160 2960);
PAINT MONO (-9160 2960);
FORCEPROP 0 LASTPIN (-9150 2900) $PN D12
J 2
(-9160 2910);
DISPLAY 0.489362 (-9160 2910);
PAINT MONO (-9160 2910);
FORCEPROP 0 LASTPIN (-9150 2850) $PN D13
J 2
(-9160 2860);
DISPLAY 0.489362 (-9160 2860);
PAINT MONO (-9160 2860);
FORCEPROP 0 LASTPIN (-9150 2800) $PN D16
J 2
(-9160 2810);
DISPLAY 0.489362 (-9160 2810);
PAINT MONO (-9160 2810);
FORCEPROP 0 LASTPIN (-9150 2750) $PN D17
J 2
(-9160 2760);
DISPLAY 0.489362 (-9160 2760);
PAINT MONO (-9160 2760);
FORCEPROP 0 LASTPIN (-9150 2700) $PN D19
J 2
(-9160 2710);
DISPLAY 0.489362 (-9160 2710);
PAINT MONO (-9160 2710);
FORCEPROP 0 LASTPIN (-9150 2650) $PN D20
J 2
(-9160 2660);
DISPLAY 0.489362 (-9160 2660);
PAINT MONO (-9160 2660);
FORCEPROP 0 LASTPIN (-9150 2600) $PN D21
J 2
(-9160 2610);
DISPLAY 0.489362 (-9160 2610);
PAINT MONO (-9160 2610);
FORCEPROP 0 LASTPIN (-9150 2550) $PN D24
J 2
(-9160 2560);
DISPLAY 0.489362 (-9160 2560);
PAINT MONO (-9160 2560);
FORCEPROP 0 LASTPIN (-9150 2500) $PN D25
J 2
(-9160 2510);
DISPLAY 0.489362 (-9160 2510);
PAINT MONO (-9160 2510);
FORCEPROP 0 LASTPIN (-9150 2450) $PN D26
J 2
(-9160 2460);
DISPLAY 0.489362 (-9160 2460);
PAINT MONO (-9160 2460);
FORCEPROP 0 LASTPIN (-9150 2400) $PN D27
J 2
(-9160 2410);
DISPLAY 0.489362 (-9160 2410);
PAINT MONO (-9160 2410);
FORCEPROP 0 LASTPIN (-9150 2350) $PN D28
J 2
(-9160 2360);
DISPLAY 0.489362 (-9160 2360);
PAINT MONO (-9160 2360);
FORCEPROP 0 LASTPIN (-9150 2300) $PN D29
J 2
(-9160 2310);
DISPLAY 0.489362 (-9160 2310);
PAINT MONO (-9160 2310);
FORCEPROP 0 LASTPIN (-9150 2250) $PN D30
J 2
(-9160 2260);
DISPLAY 0.489362 (-9160 2260);
PAINT MONO (-9160 2260);
FORCEPROP 0 LASTPIN (-9150 2200) $PN D31
J 2
(-9160 2210);
DISPLAY 0.489362 (-9160 2210);
PAINT MONO (-9160 2210);
FORCEPROP 0 LASTPIN (-9150 2150) $PN D35
J 2
(-9160 2160);
DISPLAY 0.489362 (-9160 2160);
PAINT MONO (-9160 2160);
FORCEPROP 0 LASTPIN (-9150 2100) $PN D37
J 2
(-9160 2110);
DISPLAY 0.489362 (-9160 2110);
PAINT MONO (-9160 2110);
FORCEPROP 0 LASTPIN (-9150 2050) $PN D39
J 2
(-9160 2060);
DISPLAY 0.489362 (-9160 2060);
PAINT MONO (-9160 2060);
FORCEPROP 0 LASTPIN (-9150 2000) $PN D40
J 2
(-9160 2010);
DISPLAY 0.489362 (-9160 2010);
PAINT MONO (-9160 2010);
FORCEPROP 0 LASTPIN (-9150 1950) $PN D41
J 2
(-9160 1960);
DISPLAY 0.489362 (-9160 1960);
PAINT MONO (-9160 1960);
FORCEPROP 0 LASTPIN (-9150 1900) $PN D42
J 2
(-9160 1910);
DISPLAY 0.489362 (-9160 1910);
PAINT MONO (-9160 1910);
FORCEPROP 0 LASTPIN (-9150 1850) $PN D43
J 2
(-9160 1860);
DISPLAY 0.489362 (-9160 1860);
PAINT MONO (-9160 1860);
FORCEPROP 0 LASTPIN (-9150 1800) $PN D44
J 2
(-9160 1810);
DISPLAY 0.489362 (-9160 1810);
PAINT MONO (-9160 1810);
FORCEPROP 0 LASTPIN (-9150 1750) $PN D45
J 2
(-9160 1760);
DISPLAY 0.489362 (-9160 1760);
PAINT MONO (-9160 1760);
FORCEPROP 0 LASTPIN (-9150 1700) $PN D46
J 2
(-9160 1710);
DISPLAY 0.489362 (-9160 1710);
PAINT MONO (-9160 1710);
FORCEPROP 0 LASTPIN (-9150 1650) $PN D47
J 2
(-9160 1660);
DISPLAY 0.489362 (-9160 1660);
PAINT MONO (-9160 1660);
FORCEPROP 0 LASTPIN (-9150 1600) $PN D48
J 2
(-9160 1610);
DISPLAY 0.489362 (-9160 1610);
PAINT MONO (-9160 1610);
FORCEPROP 0 LASTPIN (-9150 1550) $PN D49
J 2
(-9160 1560);
DISPLAY 0.489362 (-9160 1560);
PAINT MONO (-9160 1560);
FORCEPROP 0 LASTPIN (-9150 1500) $PN D50
J 2
(-9160 1510);
DISPLAY 0.489362 (-9160 1510);
PAINT MONO (-9160 1510);
FORCEPROP 0 LASTPIN (-9150 1450) $PN D51
J 2
(-9160 1460);
DISPLAY 0.489362 (-9160 1460);
PAINT MONO (-9160 1460);
FORCEPROP 0 LASTPIN (-9150 1400) $PN D52
J 2
(-9160 1410);
DISPLAY 0.489362 (-9160 1410);
PAINT MONO (-9160 1410);
FORCEPROP 0 LASTPIN (-9150 1350) $PN D53
J 2
(-9160 1360);
DISPLAY 0.489362 (-9160 1360);
PAINT MONO (-9160 1360);
FORCEPROP 0 LASTPIN (-9150 1300) $PN D54
J 2
(-9160 1310);
DISPLAY 0.489362 (-9160 1310);
PAINT MONO (-9160 1310);
FORCEPROP 0 LASTPIN (-9150 1250) $PN D57
J 2
(-9160 1260);
DISPLAY 0.489362 (-9160 1260);
PAINT MONO (-9160 1260);
FORCEPROP 0 LASTPIN (-9150 1200) $PN D59
J 2
(-9160 1210);
DISPLAY 0.489362 (-9160 1210);
PAINT MONO (-9160 1210);
FORCEPROP 0 LASTPIN (-9150 1150) $PN D60
J 2
(-9160 1160);
DISPLAY 0.489362 (-9160 1160);
PAINT MONO (-9160 1160);
FORCEPROP 0 LASTPIN (-9150 1100) $PN D61
J 2
(-9160 1110);
DISPLAY 0.489362 (-9160 1110);
PAINT MONO (-9160 1110);
FORCEPROP 0 LASTPIN (-9150 1050) $PN D63
J 2
(-9160 1060);
DISPLAY 0.489362 (-9160 1060);
PAINT MONO (-9160 1060);
FORCEPROP 0 LASTPIN (-9150 1000) $PN D64
J 2
(-9160 1010);
DISPLAY 0.489362 (-9160 1010);
PAINT MONO (-9160 1010);
FORCEPROP 0 LASTPIN (-9150 950) $PN D66
J 2
(-9160 960);
DISPLAY 0.489362 (-9160 960);
PAINT MONO (-9160 960);
FORCEPROP 0 LASTPIN (-9150 900) $PN D67
J 2
(-9160 910);
DISPLAY 0.489362 (-9160 910);
PAINT MONO (-9160 910);
FORCEPROP 0 LASTPIN (-9150 850) $PN D70
J 2
(-9160 860);
DISPLAY 0.489362 (-9160 860);
PAINT MONO (-9160 860);
FORCEPROP 0 LASTPIN (-9150 800) $PN D71
J 2
(-9160 810);
DISPLAY 0.489362 (-9160 810);
PAINT MONO (-9160 810);
FORCEPROP 0 LASTPIN (-9150 750) $PN D73
J 2
(-9160 760);
DISPLAY 0.489362 (-9160 760);
PAINT MONO (-9160 760);
FORCEPROP 0 LASTPIN (-9150 700) $PN D74
J 2
(-9160 710);
DISPLAY 0.489362 (-9160 710);
PAINT MONO (-9160 710);
FORCEPROP 0 LASTPIN (-9150 650) $PN E1
J 2
(-9160 660);
DISPLAY 0.489362 (-9160 660);
PAINT MONO (-9160 660);
FORCEPROP 0 LASTPIN (-9150 600) $PN E3
J 2
(-9160 610);
DISPLAY 0.489362 (-9160 610);
PAINT MONO (-9160 610);
FORCEPROP 0 LASTPIN (-9150 550) $PN E6
J 2
(-9160 560);
DISPLAY 0.489362 (-9160 560);
PAINT MONO (-9160 560);
FORCEPROP 0 LASTPIN (-9150 500) $PN E7
J 2
(-9160 510);
DISPLAY 0.489362 (-9160 510);
PAINT MONO (-9160 510);
FORCEPROP 0 LASTPIN (-9150 450) $PN E8
J 2
(-9160 460);
DISPLAY 0.489362 (-9160 460);
PAINT MONO (-9160 460);
FORCEPROP 0 LASTPIN (-8050 6350) $PN E10
J 0
(-8040 6360);
DISPLAY 0.489362 (-8040 6360);
PAINT MONO (-8040 6360);
FORCEPROP 0 LASTPIN (-8050 6300) $PN E13
J 0
(-8040 6310);
DISPLAY 0.489362 (-8040 6310);
PAINT MONO (-8040 6310);
FORCEPROP 0 LASTPIN (-8050 6250) $PN E14
J 0
(-8040 6260);
DISPLAY 0.489362 (-8040 6260);
PAINT MONO (-8040 6260);
FORCEPROP 0 LASTPIN (-8050 6200) $PN E15
J 0
(-8040 6210);
DISPLAY 0.489362 (-8040 6210);
PAINT MONO (-8040 6210);
FORCEPROP 0 LASTPIN (-8050 6150) $PN E17
J 0
(-8040 6160);
DISPLAY 0.489362 (-8040 6160);
PAINT MONO (-8040 6160);
FORCEPROP 0 LASTPIN (-8050 6100) $PN E18
J 0
(-8040 6110);
DISPLAY 0.489362 (-8040 6110);
PAINT MONO (-8040 6110);
FORCEPROP 0 LASTPIN (-8050 6050) $PN E20
J 0
(-8040 6060);
DISPLAY 0.489362 (-8040 6060);
PAINT MONO (-8040 6060);
FORCEPROP 0 LASTPIN (-8050 6000) $PN E21
J 0
(-8040 6010);
DISPLAY 0.489362 (-8040 6010);
PAINT MONO (-8040 6010);
FORCEPROP 0 LASTPIN (-8050 5950) $PN E52
J 0
(-8040 5960);
DISPLAY 0.489362 (-8040 5960);
PAINT MONO (-8040 5960);
FORCEPROP 0 LASTPIN (-8050 5900) $PN E53
J 0
(-8040 5910);
DISPLAY 0.489362 (-8040 5910);
PAINT MONO (-8040 5910);
FORCEPROP 0 LASTPIN (-8050 5850) $PN E55
J 0
(-8040 5860);
DISPLAY 0.489362 (-8040 5860);
PAINT MONO (-8040 5860);
FORCEPROP 0 LASTPIN (-8050 5800) $PN E56
J 0
(-8040 5810);
DISPLAY 0.489362 (-8040 5810);
PAINT MONO (-8040 5810);
FORCEPROP 0 LASTPIN (-8050 5750) $PN E58
J 0
(-8040 5760);
DISPLAY 0.489362 (-8040 5760);
PAINT MONO (-8040 5760);
FORCEPROP 0 LASTPIN (-8050 5700) $PN E59
J 0
(-8040 5710);
DISPLAY 0.489362 (-8040 5710);
PAINT MONO (-8040 5710);
FORCEPROP 0 LASTPIN (-8050 5650) $PN E61
J 0
(-8040 5660);
DISPLAY 0.489362 (-8040 5660);
PAINT MONO (-8040 5660);
FORCEPROP 0 LASTPIN (-8050 5600) $PN E62
J 0
(-8040 5610);
DISPLAY 0.489362 (-8040 5610);
PAINT MONO (-8040 5610);
FORCEPROP 0 LASTPIN (-8050 5550) $PN E63
J 0
(-8040 5560);
DISPLAY 0.489362 (-8040 5560);
PAINT MONO (-8040 5560);
FORCEPROP 0 LASTPIN (-8050 5500) $PN E65
J 0
(-8040 5510);
DISPLAY 0.489362 (-8040 5510);
PAINT MONO (-8040 5510);
FORCEPROP 0 LASTPIN (-8050 5450) $PN E66
J 0
(-8040 5460);
DISPLAY 0.489362 (-8040 5460);
PAINT MONO (-8040 5460);
FORCEPROP 0 LASTPIN (-8050 5400) $PN E68
J 0
(-8040 5410);
DISPLAY 0.489362 (-8040 5410);
PAINT MONO (-8040 5410);
FORCEPROP 0 LASTPIN (-8050 5350) $PN E69
J 0
(-8040 5360);
DISPLAY 0.489362 (-8040 5360);
PAINT MONO (-8040 5360);
FORCEPROP 0 LASTPIN (-8050 5300) $PN E70
J 0
(-8040 5310);
DISPLAY 0.489362 (-8040 5310);
PAINT MONO (-8040 5310);
FORCEPROP 0 LASTPIN (-8050 5250) $PN E72
J 0
(-8040 5260);
DISPLAY 0.489362 (-8040 5260);
PAINT MONO (-8040 5260);
FORCEPROP 0 LASTPIN (-8050 5200) $PN E73
J 0
(-8040 5210);
DISPLAY 0.489362 (-8040 5210);
PAINT MONO (-8040 5210);
FORCEPROP 0 LASTPIN (-8050 5150) $PN E75
J 0
(-8040 5160);
DISPLAY 0.489362 (-8040 5160);
PAINT MONO (-8040 5160);
FORCEPROP 0 LASTPIN (-8050 5100) $PN F3
J 0
(-8040 5110);
DISPLAY 0.489362 (-8040 5110);
PAINT MONO (-8040 5110);
FORCEPROP 0 LASTPIN (-8050 5050) $PN F5
J 0
(-8040 5060);
DISPLAY 0.489362 (-8040 5060);
PAINT MONO (-8040 5060);
FORCEPROP 0 LASTPIN (-8050 5000) $PN F8
J 0
(-8040 5010);
DISPLAY 0.489362 (-8040 5010);
PAINT MONO (-8040 5010);
FORCEPROP 0 LASTPIN (-8050 4950) $PN F10
J 0
(-8040 4960);
DISPLAY 0.489362 (-8040 4960);
PAINT MONO (-8040 4960);
FORCEPROP 0 LASTPIN (-8050 4900) $PN F12
J 0
(-8040 4910);
DISPLAY 0.489362 (-8040 4910);
PAINT MONO (-8040 4910);
FORCEPROP 0 LASTPIN (-8050 4850) $PN F15
J 0
(-8040 4860);
DISPLAY 0.489362 (-8040 4860);
PAINT MONO (-8040 4860);
FORCEPROP 0 LASTPIN (-8050 4800) $PN F17
J 0
(-8040 4810);
DISPLAY 0.489362 (-8040 4810);
PAINT MONO (-8040 4810);
FORCEPROP 0 LASTPIN (-8050 4750) $PN F19
J 0
(-8040 4760);
DISPLAY 0.489362 (-8040 4760);
PAINT MONO (-8040 4760);
FORCEPROP 0 LASTPIN (-8050 4700) $PN F23
J 0
(-8040 4710);
DISPLAY 0.489362 (-8040 4710);
PAINT MONO (-8040 4710);
FORCEPROP 0 LASTPIN (-8050 4650) $PN F24
J 0
(-8040 4660);
DISPLAY 0.489362 (-8040 4660);
PAINT MONO (-8040 4660);
FORCEPROP 0 LASTPIN (-8050 4600) $PN F26
J 0
(-8040 4610);
DISPLAY 0.489362 (-8040 4610);
PAINT MONO (-8040 4610);
FORCEPROP 0 LASTPIN (-8050 4550) $PN F27
J 0
(-8040 4560);
DISPLAY 0.489362 (-8040 4560);
PAINT MONO (-8040 4560);
FORCEPROP 0 LASTPIN (-8050 4500) $PN F29
J 0
(-8040 4510);
DISPLAY 0.489362 (-8040 4510);
PAINT MONO (-8040 4510);
FORCEPROP 0 LASTPIN (-8050 4450) $PN F30
J 0
(-8040 4460);
DISPLAY 0.489362 (-8040 4460);
PAINT MONO (-8040 4460);
FORCEPROP 0 LASTPIN (-8050 4400) $PN F32
J 0
(-8040 4410);
DISPLAY 0.489362 (-8040 4410);
PAINT MONO (-8040 4410);
FORCEPROP 0 LASTPIN (-8050 4350) $PN F33
J 0
(-8040 4360);
DISPLAY 0.489362 (-8040 4360);
PAINT MONO (-8040 4360);
FORCEPROP 0 LASTPIN (-8050 4300) $PN F35
J 0
(-8040 4310);
DISPLAY 0.489362 (-8040 4310);
PAINT MONO (-8040 4310);
FORCEPROP 0 LASTPIN (-8050 4250) $PN F36
J 0
(-8040 4260);
DISPLAY 0.489362 (-8040 4260);
PAINT MONO (-8040 4260);
FORCEPROP 0 LASTPIN (-8050 4200) $PN F37
J 0
(-8040 4210);
DISPLAY 0.489362 (-8040 4210);
PAINT MONO (-8040 4210);
FORCEPROP 0 LASTPIN (-8050 4150) $PN F39
J 0
(-8040 4160);
DISPLAY 0.489362 (-8040 4160);
PAINT MONO (-8040 4160);
FORCEPROP 0 LASTPIN (-8050 4100) $PN F40
J 0
(-8040 4110);
DISPLAY 0.489362 (-8040 4110);
PAINT MONO (-8040 4110);
FORCEPROP 0 LASTPIN (-8050 4050) $PN F41
J 0
(-8040 4060);
DISPLAY 0.489362 (-8040 4060);
PAINT MONO (-8040 4060);
FORCEPROP 0 LASTPIN (-8050 4000) $PN F43
J 0
(-8040 4010);
DISPLAY 0.489362 (-8040 4010);
PAINT MONO (-8040 4010);
FORCEPROP 0 LASTPIN (-8050 3950) $PN F44
J 0
(-8040 3960);
DISPLAY 0.489362 (-8040 3960);
PAINT MONO (-8040 3960);
FORCEPROP 0 LASTPIN (-8050 3900) $PN F46
J 0
(-8040 3910);
DISPLAY 0.489362 (-8040 3910);
PAINT MONO (-8040 3910);
FORCEPROP 0 LASTPIN (-8050 3850) $PN F47
J 0
(-8040 3860);
DISPLAY 0.489362 (-8040 3860);
PAINT MONO (-8040 3860);
FORCEPROP 0 LASTPIN (-8050 3800) $PN F49
J 0
(-8040 3810);
DISPLAY 0.489362 (-8040 3810);
PAINT MONO (-8040 3810);
FORCEPROP 0 LASTPIN (-8050 3750) $PN F50
J 0
(-8040 3760);
DISPLAY 0.489362 (-8040 3760);
PAINT MONO (-8040 3760);
FORCEPROP 0 LASTPIN (-8050 3700) $PN F52
J 0
(-8040 3710);
DISPLAY 0.489362 (-8040 3710);
PAINT MONO (-8040 3710);
FORCEPROP 0 LASTPIN (-8050 3650) $PN F53
J 0
(-8040 3660);
DISPLAY 0.489362 (-8040 3660);
PAINT MONO (-8040 3660);
FORCEPROP 0 LASTPIN (-8050 3600) $PN F57
J 0
(-8040 3610);
DISPLAY 0.489362 (-8040 3610);
PAINT MONO (-8040 3610);
FORCEPROP 0 LASTPIN (-8050 3550) $PN F59
J 0
(-8040 3560);
DISPLAY 0.489362 (-8040 3560);
PAINT MONO (-8040 3560);
FORCEPROP 0 LASTPIN (-8050 3500) $PN F61
J 0
(-8040 3510);
DISPLAY 0.489362 (-8040 3510);
PAINT MONO (-8040 3510);
FORCEPROP 0 LASTPIN (-8050 3450) $PN F64
J 0
(-8040 3460);
DISPLAY 0.489362 (-8040 3460);
PAINT MONO (-8040 3460);
FORCEPROP 0 LASTPIN (-8050 3400) $PN F66
J 0
(-8040 3410);
DISPLAY 0.489362 (-8040 3410);
PAINT MONO (-8040 3410);
FORCEPROP 0 LASTPIN (-8050 3350) $PN F68
J 0
(-8040 3360);
DISPLAY 0.489362 (-8040 3360);
PAINT MONO (-8040 3360);
FORCEPROP 0 LASTPIN (-8050 3300) $PN F71
J 0
(-8040 3310);
DISPLAY 0.489362 (-8040 3310);
PAINT MONO (-8040 3310);
FORCEPROP 0 LASTPIN (-8050 3250) $PN F73
J 0
(-8040 3260);
DISPLAY 0.489362 (-8040 3260);
PAINT MONO (-8040 3260);
FORCEPROP 0 LASTPIN (-8050 3200) $PN G1
J 0
(-8040 3210);
DISPLAY 0.489362 (-8040 3210);
PAINT MONO (-8040 3210);
FORCEPROP 0 LASTPIN (-8050 3150) $PN G4
J 0
(-8040 3160);
DISPLAY 0.489362 (-8040 3160);
PAINT MONO (-8040 3160);
FORCEPROP 0 LASTPIN (-8050 3100) $PN G6
J 0
(-8040 3110);
DISPLAY 0.489362 (-8040 3110);
PAINT MONO (-8040 3110);
FORCEPROP 0 LASTPIN (-8050 3050) $PN G8
J 0
(-8040 3060);
DISPLAY 0.489362 (-8040 3060);
PAINT MONO (-8040 3060);
FORCEPROP 0 LASTPIN (-8050 3000) $PN G11
J 0
(-8040 3010);
DISPLAY 0.489362 (-8040 3010);
PAINT MONO (-8040 3010);
FORCEPROP 0 LASTPIN (-8050 2950) $PN G13
J 0
(-8040 2960);
DISPLAY 0.489362 (-8040 2960);
PAINT MONO (-8040 2960);
FORCEPROP 0 LASTPIN (-8050 2900) $PN G15
J 0
(-8040 2910);
DISPLAY 0.489362 (-8040 2910);
PAINT MONO (-8040 2910);
FORCEPROP 0 LASTPIN (-8050 2850) $PN G18
J 0
(-8040 2860);
DISPLAY 0.489362 (-8040 2860);
PAINT MONO (-8040 2860);
FORCEPROP 0 LASTPIN (-8050 2800) $PN G20
J 0
(-8040 2810);
DISPLAY 0.489362 (-8040 2810);
PAINT MONO (-8040 2810);
FORCEPROP 0 LASTPIN (-8050 2750) $PN G22
J 0
(-8040 2760);
DISPLAY 0.489362 (-8040 2760);
PAINT MONO (-8040 2760);
FORCEPROP 0 LASTPIN (-8050 2700) $PN G25
J 0
(-8040 2710);
DISPLAY 0.489362 (-8040 2710);
PAINT MONO (-8040 2710);
FORCEPROP 0 LASTPIN (-8050 2650) $PN G28
J 0
(-8040 2660);
DISPLAY 0.489362 (-8040 2660);
PAINT MONO (-8040 2660);
FORCEPROP 0 LASTPIN (-8050 2600) $PN G31
J 0
(-8040 2610);
DISPLAY 0.489362 (-8040 2610);
PAINT MONO (-8040 2610);
FORCEPROP 0 LASTPIN (-8050 2550) $PN G34
J 0
(-8040 2560);
DISPLAY 0.489362 (-8040 2560);
PAINT MONO (-8040 2560);
FORCEPROP 0 LASTPIN (-8050 2500) $PN G42
J 0
(-8040 2510);
DISPLAY 0.489362 (-8040 2510);
PAINT MONO (-8040 2510);
FORCEPROP 0 LASTPIN (-8050 2450) $PN G45
J 0
(-8040 2460);
DISPLAY 0.489362 (-8040 2460);
PAINT MONO (-8040 2460);
FORCEPROP 0 LASTPIN (-8050 2400) $PN G48
J 0
(-8040 2410);
DISPLAY 0.489362 (-8040 2410);
PAINT MONO (-8040 2410);
FORCEPROP 0 LASTPIN (-8050 2350) $PN G51
J 0
(-8040 2360);
DISPLAY 0.489362 (-8040 2360);
PAINT MONO (-8040 2360);
FORCEPROP 0 LASTPIN (-8050 2300) $PN G54
J 0
(-8040 2310);
DISPLAY 0.489362 (-8040 2310);
PAINT MONO (-8040 2310);
FORCEPROP 0 LASTPIN (-8050 2250) $PN G56
J 0
(-8040 2260);
DISPLAY 0.489362 (-8040 2260);
PAINT MONO (-8040 2260);
FORCEPROP 0 LASTPIN (-8050 2200) $PN G58
J 0
(-8040 2210);
DISPLAY 0.489362 (-8040 2210);
PAINT MONO (-8040 2210);
FORCEPROP 0 LASTPIN (-8050 2150) $PN G61
J 0
(-8040 2160);
DISPLAY 0.489362 (-8040 2160);
PAINT MONO (-8040 2160);
FORCEPROP 0 LASTPIN (-8050 2100) $PN G63
J 0
(-8040 2110);
DISPLAY 0.489362 (-8040 2110);
PAINT MONO (-8040 2110);
FORCEPROP 0 LASTPIN (-8050 2050) $PN G65
J 0
(-8040 2060);
DISPLAY 0.489362 (-8040 2060);
PAINT MONO (-8040 2060);
FORCEPROP 0 LASTPIN (-8050 2000) $PN G68
J 0
(-8040 2010);
DISPLAY 0.489362 (-8040 2010);
PAINT MONO (-8040 2010);
FORCEPROP 0 LASTPIN (-8050 1950) $PN G70
J 0
(-8040 1960);
DISPLAY 0.489362 (-8040 1960);
PAINT MONO (-8040 1960);
FORCEPROP 0 LASTPIN (-8050 1900) $PN G72
J 0
(-8040 1910);
DISPLAY 0.489362 (-8040 1910);
PAINT MONO (-8040 1910);
FORCEPROP 0 LASTPIN (-8050 1850) $PN G75
J 0
(-8040 1860);
DISPLAY 0.489362 (-8040 1860);
PAINT MONO (-8040 1860);
FORCEPROP 0 LASTPIN (-8050 1800) $PN H3
J 0
(-8040 1810);
DISPLAY 0.489362 (-8040 1810);
PAINT MONO (-8040 1810);
FORCEPROP 0 LASTPIN (-8050 1750) $PN H8
J 0
(-8040 1760);
DISPLAY 0.489362 (-8040 1760);
PAINT MONO (-8040 1760);
FORCEPROP 0 LASTPIN (-8050 1700) $PN H10
J 0
(-8040 1710);
DISPLAY 0.489362 (-8040 1710);
PAINT MONO (-8040 1710);
FORCEPROP 0 LASTPIN (-8050 1650) $PN H15
J 0
(-8040 1660);
DISPLAY 0.489362 (-8040 1660);
PAINT MONO (-8040 1660);
FORCEPROP 0 LASTPIN (-8050 1600) $PN H17
J 0
(-8040 1610);
DISPLAY 0.489362 (-8040 1610);
PAINT MONO (-8040 1610);
FORCEPROP 0 LASTPIN (-8050 1550) $PN H22
J 0
(-8040 1560);
DISPLAY 0.489362 (-8040 1560);
PAINT MONO (-8040 1560);
FORCEPROP 0 LASTPIN (-8050 1500) $PN H25
J 0
(-8040 1510);
DISPLAY 0.489362 (-8040 1510);
PAINT MONO (-8040 1510);
FORCEPROP 0 LASTPIN (-8050 1450) $PN H28
J 0
(-8040 1460);
DISPLAY 0.489362 (-8040 1460);
PAINT MONO (-8040 1460);
FORCEPROP 0 LASTPIN (-8050 1400) $PN H31
J 0
(-8040 1410);
DISPLAY 0.489362 (-8040 1410);
PAINT MONO (-8040 1410);
FORCEPROP 0 LASTPIN (-8050 1350) $PN H34
J 0
(-8040 1360);
DISPLAY 0.489362 (-8040 1360);
PAINT MONO (-8040 1360);
FORCEPROP 0 LASTPIN (-8050 1300) $PN H37
J 0
(-8040 1310);
DISPLAY 0.489362 (-8040 1310);
PAINT MONO (-8040 1310);
FORCEPROP 0 LASTPIN (-8050 1250) $PN H39
J 0
(-8040 1260);
DISPLAY 0.489362 (-8040 1260);
PAINT MONO (-8040 1260);
FORCEPROP 0 LASTPIN (-8050 1200) $PN H42
J 0
(-8040 1210);
DISPLAY 0.489362 (-8040 1210);
PAINT MONO (-8040 1210);
FORCEPROP 0 LASTPIN (-8050 1150) $PN H45
J 0
(-8040 1160);
DISPLAY 0.489362 (-8040 1160);
PAINT MONO (-8040 1160);
FORCEPROP 0 LASTPIN (-8050 1100) $PN H48
J 0
(-8040 1110);
DISPLAY 0.489362 (-8040 1110);
PAINT MONO (-8040 1110);
FORCEPROP 0 LASTPIN (-8050 1050) $PN H51
J 0
(-8040 1060);
DISPLAY 0.489362 (-8040 1060);
PAINT MONO (-8040 1060);
FORCEPROP 0 LASTPIN (-8050 1000) $PN H54
J 0
(-8040 1010);
DISPLAY 0.489362 (-8040 1010);
PAINT MONO (-8040 1010);
FORCEPROP 0 LASTPIN (-8050 950) $PN H59
J 0
(-8040 960);
DISPLAY 0.489362 (-8040 960);
PAINT MONO (-8040 960);
FORCEPROP 0 LASTPIN (-8050 900) $PN H61
J 0
(-8040 910);
DISPLAY 0.489362 (-8040 910);
PAINT MONO (-8040 910);
FORCEPROP 0 LASTPIN (-8050 850) $PN H66
J 0
(-8040 860);
DISPLAY 0.489362 (-8040 860);
PAINT MONO (-8040 860);
FORCEPROP 0 LASTPIN (-8050 800) $PN H68
J 0
(-8040 810);
DISPLAY 0.489362 (-8040 810);
PAINT MONO (-8040 810);
FORCEPROP 0 LASTPIN (-8050 750) $PN H73
J 0
(-8040 760);
DISPLAY 0.489362 (-8040 760);
PAINT MONO (-8040 760);
FORCEPROP 0 LASTPIN (-8050 700) $PN J1
J 0
(-8040 710);
DISPLAY 0.489362 (-8040 710);
PAINT MONO (-8040 710);
FORCEPROP 0 LASTPIN (-8050 650) $PN J4
J 0
(-8040 660);
DISPLAY 0.489362 (-8040 660);
PAINT MONO (-8040 660);
FORCEPROP 0 LASTPIN (-8050 600) $PN J6
J 0
(-8040 610);
DISPLAY 0.489362 (-8040 610);
PAINT MONO (-8040 610);
FORCEPROP 0 LASTPIN (-8050 550) $PN J8
J 0
(-8040 560);
DISPLAY 0.489362 (-8040 560);
PAINT MONO (-8040 560);
FORCEPROP 0 LASTPIN (-8050 500) $PN J11
J 0
(-8040 510);
DISPLAY 0.489362 (-8040 510);
PAINT MONO (-8040 510);
FORCEPROP 0 LASTPIN (-8050 450) $PN J13
J 0
(-8040 460);
DISPLAY 0.489362 (-8040 460);
PAINT MONO (-8040 460);
FORCEPROP 2 LAST PART_TYPE SMLF
J 0
(-9000 6700);
DISPLAY 1.021277 (-9000 6700);
FORCEPROP 1 LAST MATERIAL IO
J 0
(-8995 6482);
DISPLAY 0.489362 (-8995 6482);
PAINT SKYBLUE (-8995 6482);
FORCEPROP 2 LAST VALUE SOCKET6096_13568-001
J 0
(-9000 6550);
DISPLAY 0.489362 (-9000 6550);
PAINT SKYBLUE (-9000 6550);
FORCEPROP 1 LAST PART_NUMBER DGA^6000030
J 0
(-9000 6650);
DISPLAY 0.489362 (-9000 6650);
PAINT SKYBLUE (-9000 6650);
FORCEPROP 2 LAST CDS_LIB pure_quanta
J 0
(-8600 3400);
DISPLAY INVISIBLE (-8600 3400);
FORCEPROP 1 LAST CDS_LMAN_SYM_OUTLINE -400,3050,400,-3050
J 0
(-8600 3400);
DISPLAY 0.468085 (-8600 3400);
PAINT GREEN (-8600 3400);
DISPLAY INVISIBLE (-8600 3400);
FORCEPROP 1 LAST NEEDS_NO_SIZE TRUE
J 0
(-8600 3400);
DISPLAY 0.723404 (-8600 3400);
PAINT GREEN (-8600 3400);
DISPLAY INVISIBLE (-8600 3400);
FORCEPROP 1 LAST PATH I19
J 0
(-8600 3400);
DISPLAY 0.723404 (-8600 3400);
PAINT GREEN (-8600 3400);
DISPLAY INVISIBLE (-8600 3400);
FORCEADD GENOA_SP5..29
(-7075 3425);
FORCEPROP 1 LAST LOCATION U25
J 0
(-7470 6600);
DISPLAY 0.489362 (-7470 6600);
PAINT SKYBLUE (-7470 6600);
FORCEPROP 0 LAST $SEC 29
J 0
(-7450 6825);
DISPLAY 0.680851 (-7450 6825);
PAINT MONO (-7450 6825);
DISPLAY INVISIBLE (-7450 6825);
FORCEPROP 0 LAST CDS_SEC 29
J 0
(-7475 6725);
DISPLAY 1.021277 (-7475 6725);
DISPLAY INVISIBLE (-7475 6725);
FORCEPROP 0 LASTPIN (-7625 6275) $PN J15
J 2
(-7635 6285);
DISPLAY 0.489362 (-7635 6285);
PAINT MONO (-7635 6285);
FORCEPROP 0 LASTPIN (-7625 6225) $PN J18
J 2
(-7635 6235);
DISPLAY 0.489362 (-7635 6235);
PAINT MONO (-7635 6235);
FORCEPROP 0 LASTPIN (-7625 6175) $PN J20
J 2
(-7635 6185);
DISPLAY 0.489362 (-7635 6185);
PAINT MONO (-7635 6185);
FORCEPROP 0 LASTPIN (-7625 6125) $PN J22
J 2
(-7635 6135);
DISPLAY 0.489362 (-7635 6135);
PAINT MONO (-7635 6135);
FORCEPROP 0 LASTPIN (-7625 6075) $PN J25
J 2
(-7635 6085);
DISPLAY 0.489362 (-7635 6085);
PAINT MONO (-7635 6085);
FORCEPROP 0 LASTPIN (-7625 6025) $PN J28
J 2
(-7635 6035);
DISPLAY 0.489362 (-7635 6035);
PAINT MONO (-7635 6035);
FORCEPROP 0 LASTPIN (-7625 5975) $PN J31
J 2
(-7635 5985);
DISPLAY 0.489362 (-7635 5985);
PAINT MONO (-7635 5985);
FORCEPROP 0 LASTPIN (-7625 5925) $PN J34
J 2
(-7635 5935);
DISPLAY 0.489362 (-7635 5935);
PAINT MONO (-7635 5935);
FORCEPROP 0 LASTPIN (-7625 5875) $PN J42
J 2
(-7635 5885);
DISPLAY 0.489362 (-7635 5885);
PAINT MONO (-7635 5885);
FORCEPROP 0 LASTPIN (-7625 5825) $PN J45
J 2
(-7635 5835);
DISPLAY 0.489362 (-7635 5835);
PAINT MONO (-7635 5835);
FORCEPROP 0 LASTPIN (-7625 5775) $PN J48
J 2
(-7635 5785);
DISPLAY 0.489362 (-7635 5785);
PAINT MONO (-7635 5785);
FORCEPROP 0 LASTPIN (-7625 5725) $PN J51
J 2
(-7635 5735);
DISPLAY 0.489362 (-7635 5735);
PAINT MONO (-7635 5735);
FORCEPROP 0 LASTPIN (-7625 5675) $PN J54
J 2
(-7635 5685);
DISPLAY 0.489362 (-7635 5685);
PAINT MONO (-7635 5685);
FORCEPROP 0 LASTPIN (-7625 5625) $PN J56
J 2
(-7635 5635);
DISPLAY 0.489362 (-7635 5635);
PAINT MONO (-7635 5635);
FORCEPROP 0 LASTPIN (-7625 5575) $PN J58
J 2
(-7635 5585);
DISPLAY 0.489362 (-7635 5585);
PAINT MONO (-7635 5585);
FORCEPROP 0 LASTPIN (-7625 5525) $PN J61
J 2
(-7635 5535);
DISPLAY 0.489362 (-7635 5535);
PAINT MONO (-7635 5535);
FORCEPROP 0 LASTPIN (-7625 5475) $PN J63
J 2
(-7635 5485);
DISPLAY 0.489362 (-7635 5485);
PAINT MONO (-7635 5485);
FORCEPROP 0 LASTPIN (-7625 5425) $PN J65
J 2
(-7635 5435);
DISPLAY 0.489362 (-7635 5435);
PAINT MONO (-7635 5435);
FORCEPROP 0 LASTPIN (-7625 5375) $PN J68
J 2
(-7635 5385);
DISPLAY 0.489362 (-7635 5385);
PAINT MONO (-7635 5385);
FORCEPROP 0 LASTPIN (-7625 5325) $PN J70
J 2
(-7635 5335);
DISPLAY 0.489362 (-7635 5335);
PAINT MONO (-7635 5335);
FORCEPROP 0 LASTPIN (-7625 5275) $PN J72
J 2
(-7635 5285);
DISPLAY 0.489362 (-7635 5285);
PAINT MONO (-7635 5285);
FORCEPROP 0 LASTPIN (-7625 5225) $PN J75
J 2
(-7635 5235);
DISPLAY 0.489362 (-7635 5235);
PAINT MONO (-7635 5235);
FORCEPROP 0 LASTPIN (-7625 5175) $PN K3
J 2
(-7635 5185);
DISPLAY 0.489362 (-7635 5185);
PAINT MONO (-7635 5185);
FORCEPROP 0 LASTPIN (-7625 5125) $PN K5
J 2
(-7635 5135);
DISPLAY 0.489362 (-7635 5135);
PAINT MONO (-7635 5135);
FORCEPROP 0 LASTPIN (-7625 5075) $PN K8
J 2
(-7635 5085);
DISPLAY 0.489362 (-7635 5085);
PAINT MONO (-7635 5085);
FORCEPROP 0 LASTPIN (-7625 5025) $PN K10
J 2
(-7635 5035);
DISPLAY 0.489362 (-7635 5035);
PAINT MONO (-7635 5035);
FORCEPROP 0 LASTPIN (-7625 4975) $PN K12
J 2
(-7635 4985);
DISPLAY 0.489362 (-7635 4985);
PAINT MONO (-7635 4985);
FORCEPROP 0 LASTPIN (-7625 4925) $PN K15
J 2
(-7635 4935);
DISPLAY 0.489362 (-7635 4935);
PAINT MONO (-7635 4935);
FORCEPROP 0 LASTPIN (-7625 4875) $PN K17
J 2
(-7635 4885);
DISPLAY 0.489362 (-7635 4885);
PAINT MONO (-7635 4885);
FORCEPROP 0 LASTPIN (-7625 4825) $PN K19
J 2
(-7635 4835);
DISPLAY 0.489362 (-7635 4835);
PAINT MONO (-7635 4835);
FORCEPROP 0 LASTPIN (-7625 4775) $PN K24
J 2
(-7635 4785);
DISPLAY 0.489362 (-7635 4785);
PAINT MONO (-7635 4785);
FORCEPROP 0 LASTPIN (-7625 4725) $PN K25
J 2
(-7635 4735);
DISPLAY 0.489362 (-7635 4735);
PAINT MONO (-7635 4735);
FORCEPROP 0 LASTPIN (-7625 4675) $PN K26
J 2
(-7635 4685);
DISPLAY 0.489362 (-7635 4685);
PAINT MONO (-7635 4685);
FORCEPROP 0 LASTPIN (-7625 4625) $PN K27
J 2
(-7635 4635);
DISPLAY 0.489362 (-7635 4635);
PAINT MONO (-7635 4635);
FORCEPROP 0 LASTPIN (-7625 4575) $PN K28
J 2
(-7635 4585);
DISPLAY 0.489362 (-7635 4585);
PAINT MONO (-7635 4585);
FORCEPROP 0 LASTPIN (-7625 4525) $PN K29
J 2
(-7635 4535);
DISPLAY 0.489362 (-7635 4535);
PAINT MONO (-7635 4535);
FORCEPROP 0 LASTPIN (-7625 4475) $PN K30
J 2
(-7635 4485);
DISPLAY 0.489362 (-7635 4485);
PAINT MONO (-7635 4485);
FORCEPROP 0 LASTPIN (-7625 4425) $PN K31
J 2
(-7635 4435);
DISPLAY 0.489362 (-7635 4435);
PAINT MONO (-7635 4435);
FORCEPROP 0 LASTPIN (-7625 4375) $PN K32
J 2
(-7635 4385);
DISPLAY 0.489362 (-7635 4385);
PAINT MONO (-7635 4385);
FORCEPROP 0 LASTPIN (-7625 4325) $PN K33
J 2
(-7635 4335);
DISPLAY 0.489362 (-7635 4335);
PAINT MONO (-7635 4335);
FORCEPROP 0 LASTPIN (-7625 4275) $PN K34
J 2
(-7635 4285);
DISPLAY 0.489362 (-7635 4285);
PAINT MONO (-7635 4285);
FORCEPROP 0 LASTPIN (-7625 4225) $PN K37
J 2
(-7635 4235);
DISPLAY 0.489362 (-7635 4235);
PAINT MONO (-7635 4235);
FORCEPROP 0 LASTPIN (-7625 4175) $PN K39
J 2
(-7635 4185);
DISPLAY 0.489362 (-7635 4185);
PAINT MONO (-7635 4185);
FORCEPROP 0 LASTPIN (-7625 4125) $PN K42
J 2
(-7635 4135);
DISPLAY 0.489362 (-7635 4135);
PAINT MONO (-7635 4135);
FORCEPROP 0 LASTPIN (-7625 4075) $PN K43
J 2
(-7635 4085);
DISPLAY 0.489362 (-7635 4085);
PAINT MONO (-7635 4085);
FORCEPROP 0 LASTPIN (-7625 4025) $PN K44
J 2
(-7635 4035);
DISPLAY 0.489362 (-7635 4035);
PAINT MONO (-7635 4035);
FORCEPROP 0 LASTPIN (-7625 3975) $PN K45
J 2
(-7635 3985);
DISPLAY 0.489362 (-7635 3985);
PAINT MONO (-7635 3985);
FORCEPROP 0 LASTPIN (-7625 3925) $PN K46
J 2
(-7635 3935);
DISPLAY 0.489362 (-7635 3935);
PAINT MONO (-7635 3935);
FORCEPROP 0 LASTPIN (-7625 3875) $PN K47
J 2
(-7635 3885);
DISPLAY 0.489362 (-7635 3885);
PAINT MONO (-7635 3885);
FORCEPROP 0 LASTPIN (-7625 3825) $PN K48
J 2
(-7635 3835);
DISPLAY 0.489362 (-7635 3835);
PAINT MONO (-7635 3835);
FORCEPROP 0 LASTPIN (-7625 3775) $PN K49
J 2
(-7635 3785);
DISPLAY 0.489362 (-7635 3785);
PAINT MONO (-7635 3785);
FORCEPROP 0 LASTPIN (-7625 3725) $PN K50
J 2
(-7635 3735);
DISPLAY 0.489362 (-7635 3735);
PAINT MONO (-7635 3735);
FORCEPROP 0 LASTPIN (-7625 3675) $PN K51
J 2
(-7635 3685);
DISPLAY 0.489362 (-7635 3685);
PAINT MONO (-7635 3685);
FORCEPROP 0 LASTPIN (-7625 3625) $PN K52
J 2
(-7635 3635);
DISPLAY 0.489362 (-7635 3635);
PAINT MONO (-7635 3635);
FORCEPROP 0 LASTPIN (-7625 3575) $PN K53
J 2
(-7635 3585);
DISPLAY 0.489362 (-7635 3585);
PAINT MONO (-7635 3585);
FORCEPROP 0 LASTPIN (-7625 3525) $PN K57
J 2
(-7635 3535);
DISPLAY 0.489362 (-7635 3535);
PAINT MONO (-7635 3535);
FORCEPROP 0 LASTPIN (-7625 3475) $PN K61
J 2
(-7635 3485);
DISPLAY 0.489362 (-7635 3485);
PAINT MONO (-7635 3485);
FORCEPROP 0 LASTPIN (-7625 3425) $PN K64
J 2
(-7635 3435);
DISPLAY 0.489362 (-7635 3435);
PAINT MONO (-7635 3435);
FORCEPROP 0 LASTPIN (-7625 3375) $PN K66
J 2
(-7635 3385);
DISPLAY 0.489362 (-7635 3385);
PAINT MONO (-7635 3385);
FORCEPROP 0 LASTPIN (-7625 3325) $PN K68
J 2
(-7635 3335);
DISPLAY 0.489362 (-7635 3335);
PAINT MONO (-7635 3335);
FORCEPROP 0 LASTPIN (-7625 3275) $PN K71
J 2
(-7635 3285);
DISPLAY 0.489362 (-7635 3285);
PAINT MONO (-7635 3285);
FORCEPROP 0 LASTPIN (-7625 3225) $PN K73
J 2
(-7635 3235);
DISPLAY 0.489362 (-7635 3235);
PAINT MONO (-7635 3235);
FORCEPROP 0 LASTPIN (-7625 3175) $PN L1
J 2
(-7635 3185);
DISPLAY 0.489362 (-7635 3185);
PAINT MONO (-7635 3185);
FORCEPROP 0 LASTPIN (-7625 3125) $PN L6
J 2
(-7635 3135);
DISPLAY 0.489362 (-7635 3135);
PAINT MONO (-7635 3135);
FORCEPROP 0 LASTPIN (-7625 3075) $PN L8
J 2
(-7635 3085);
DISPLAY 0.489362 (-7635 3085);
PAINT MONO (-7635 3085);
FORCEPROP 0 LASTPIN (-7625 3025) $PN L13
J 2
(-7635 3035);
DISPLAY 0.489362 (-7635 3035);
PAINT MONO (-7635 3035);
FORCEPROP 0 LASTPIN (-7625 2975) $PN L15
J 2
(-7635 2985);
DISPLAY 0.489362 (-7635 2985);
PAINT MONO (-7635 2985);
FORCEPROP 0 LASTPIN (-7625 2925) $PN L20
J 2
(-7635 2935);
DISPLAY 0.489362 (-7635 2935);
PAINT MONO (-7635 2935);
FORCEPROP 0 LASTPIN (-7625 2875) $PN L22
J 2
(-7635 2885);
DISPLAY 0.489362 (-7635 2885);
PAINT MONO (-7635 2885);
FORCEPROP 0 LASTPIN (-7625 2825) $PN L25
J 2
(-7635 2835);
DISPLAY 0.489362 (-7635 2835);
PAINT MONO (-7635 2835);
FORCEPROP 0 LASTPIN (-7625 2775) $PN L28
J 2
(-7635 2785);
DISPLAY 0.489362 (-7635 2785);
PAINT MONO (-7635 2785);
FORCEPROP 0 LASTPIN (-7625 2725) $PN L31
J 2
(-7635 2735);
DISPLAY 0.489362 (-7635 2735);
PAINT MONO (-7635 2735);
FORCEPROP 0 LASTPIN (-7625 2675) $PN L34
J 2
(-7635 2685);
DISPLAY 0.489362 (-7635 2685);
PAINT MONO (-7635 2685);
FORCEPROP 0 LASTPIN (-7625 2625) $PN L35
J 2
(-7635 2635);
DISPLAY 0.489362 (-7635 2635);
PAINT MONO (-7635 2635);
FORCEPROP 0 LASTPIN (-7625 2575) $PN L36
J 2
(-7635 2585);
DISPLAY 0.489362 (-7635 2585);
PAINT MONO (-7635 2585);
FORCEPROP 0 LASTPIN (-7625 2525) $PN L40
J 2
(-7635 2535);
DISPLAY 0.489362 (-7635 2535);
PAINT MONO (-7635 2535);
FORCEPROP 0 LASTPIN (-7625 2475) $PN L41
J 2
(-7635 2485);
DISPLAY 0.489362 (-7635 2485);
PAINT MONO (-7635 2485);
FORCEPROP 0 LASTPIN (-7625 2425) $PN L42
J 2
(-7635 2435);
DISPLAY 0.489362 (-7635 2435);
PAINT MONO (-7635 2435);
FORCEPROP 0 LASTPIN (-7625 2375) $PN L45
J 2
(-7635 2385);
DISPLAY 0.489362 (-7635 2385);
PAINT MONO (-7635 2385);
FORCEPROP 0 LASTPIN (-7625 2325) $PN L48
J 2
(-7635 2335);
DISPLAY 0.489362 (-7635 2335);
PAINT MONO (-7635 2335);
FORCEPROP 0 LASTPIN (-7625 2275) $PN L51
J 2
(-7635 2285);
DISPLAY 0.489362 (-7635 2285);
PAINT MONO (-7635 2285);
FORCEPROP 0 LASTPIN (-7625 2225) $PN L54
J 2
(-7635 2235);
DISPLAY 0.489362 (-7635 2235);
PAINT MONO (-7635 2235);
FORCEPROP 0 LASTPIN (-7625 2175) $PN L56
J 2
(-7635 2185);
DISPLAY 0.489362 (-7635 2185);
PAINT MONO (-7635 2185);
FORCEPROP 0 LASTPIN (-7625 2125) $PN L61
J 2
(-7635 2135);
DISPLAY 0.489362 (-7635 2135);
PAINT MONO (-7635 2135);
FORCEPROP 0 LASTPIN (-7625 2075) $PN L63
J 2
(-7635 2085);
DISPLAY 0.489362 (-7635 2085);
PAINT MONO (-7635 2085);
FORCEPROP 0 LASTPIN (-7625 2025) $PN L68
J 2
(-7635 2035);
DISPLAY 0.489362 (-7635 2035);
PAINT MONO (-7635 2035);
FORCEPROP 0 LASTPIN (-7625 1975) $PN L70
J 2
(-7635 1985);
DISPLAY 0.489362 (-7635 1985);
PAINT MONO (-7635 1985);
FORCEPROP 0 LASTPIN (-7625 1925) $PN L75
J 2
(-7635 1935);
DISPLAY 0.489362 (-7635 1935);
PAINT MONO (-7635 1935);
FORCEPROP 0 LASTPIN (-7625 1875) $PN M3
J 2
(-7635 1885);
DISPLAY 0.489362 (-7635 1885);
PAINT MONO (-7635 1885);
FORCEPROP 0 LASTPIN (-7625 1825) $PN M5
J 2
(-7635 1835);
DISPLAY 0.489362 (-7635 1835);
PAINT MONO (-7635 1835);
FORCEPROP 0 LASTPIN (-7625 1775) $PN M8
J 2
(-7635 1785);
DISPLAY 0.489362 (-7635 1785);
PAINT MONO (-7635 1785);
FORCEPROP 0 LASTPIN (-7625 1725) $PN M10
J 2
(-7635 1735);
DISPLAY 0.489362 (-7635 1735);
PAINT MONO (-7635 1735);
FORCEPROP 0 LASTPIN (-7625 1675) $PN M12
J 2
(-7635 1685);
DISPLAY 0.489362 (-7635 1685);
PAINT MONO (-7635 1685);
FORCEPROP 0 LASTPIN (-7625 1625) $PN M15
J 2
(-7635 1635);
DISPLAY 0.489362 (-7635 1635);
PAINT MONO (-7635 1635);
FORCEPROP 0 LASTPIN (-7625 1575) $PN M17
J 2
(-7635 1585);
DISPLAY 0.489362 (-7635 1585);
PAINT MONO (-7635 1585);
FORCEPROP 0 LASTPIN (-7625 1525) $PN M19
J 2
(-7635 1535);
DISPLAY 0.489362 (-7635 1535);
PAINT MONO (-7635 1535);
FORCEPROP 0 LASTPIN (-7625 1475) $PN M22
J 2
(-7635 1485);
DISPLAY 0.489362 (-7635 1485);
PAINT MONO (-7635 1485);
FORCEPROP 0 LASTPIN (-7625 1425) $PN M25
J 2
(-7635 1435);
DISPLAY 0.489362 (-7635 1435);
PAINT MONO (-7635 1435);
FORCEPROP 0 LASTPIN (-7625 1375) $PN M28
J 2
(-7635 1385);
DISPLAY 0.489362 (-7635 1385);
PAINT MONO (-7635 1385);
FORCEPROP 0 LASTPIN (-7625 1325) $PN M31
J 2
(-7635 1335);
DISPLAY 0.489362 (-7635 1335);
PAINT MONO (-7635 1335);
FORCEPROP 0 LASTPIN (-7625 1275) $PN M34
J 2
(-7635 1285);
DISPLAY 0.489362 (-7635 1285);
PAINT MONO (-7635 1285);
FORCEPROP 0 LASTPIN (-7625 1225) $PN M37
J 2
(-7635 1235);
DISPLAY 0.489362 (-7635 1235);
PAINT MONO (-7635 1235);
FORCEPROP 0 LASTPIN (-7625 1175) $PN M39
J 2
(-7635 1185);
DISPLAY 0.489362 (-7635 1185);
PAINT MONO (-7635 1185);
FORCEPROP 0 LASTPIN (-7625 1125) $PN M42
J 2
(-7635 1135);
DISPLAY 0.489362 (-7635 1135);
PAINT MONO (-7635 1135);
FORCEPROP 0 LASTPIN (-7625 1075) $PN M45
J 2
(-7635 1085);
DISPLAY 0.489362 (-7635 1085);
PAINT MONO (-7635 1085);
FORCEPROP 0 LASTPIN (-7625 1025) $PN M48
J 2
(-7635 1035);
DISPLAY 0.489362 (-7635 1035);
PAINT MONO (-7635 1035);
FORCEPROP 0 LASTPIN (-7625 975) $PN M51
J 2
(-7635 985);
DISPLAY 0.489362 (-7635 985);
PAINT MONO (-7635 985);
FORCEPROP 0 LASTPIN (-7625 925) $PN M54
J 2
(-7635 935);
DISPLAY 0.489362 (-7635 935);
PAINT MONO (-7635 935);
FORCEPROP 0 LASTPIN (-7625 875) $PN M57
J 2
(-7635 885);
DISPLAY 0.489362 (-7635 885);
PAINT MONO (-7635 885);
FORCEPROP 0 LASTPIN (-7625 825) $PN M59
J 2
(-7635 835);
DISPLAY 0.489362 (-7635 835);
PAINT MONO (-7635 835);
FORCEPROP 0 LASTPIN (-7625 775) $PN M61
J 2
(-7635 785);
DISPLAY 0.489362 (-7635 785);
PAINT MONO (-7635 785);
FORCEPROP 0 LASTPIN (-7625 725) $PN M64
J 2
(-7635 735);
DISPLAY 0.489362 (-7635 735);
PAINT MONO (-7635 735);
FORCEPROP 0 LASTPIN (-7625 675) $PN M66
J 2
(-7635 685);
DISPLAY 0.489362 (-7635 685);
PAINT MONO (-7635 685);
FORCEPROP 0 LASTPIN (-7625 625) $PN M68
J 2
(-7635 635);
DISPLAY 0.489362 (-7635 635);
PAINT MONO (-7635 635);
FORCEPROP 0 LASTPIN (-7625 575) $PN M71
J 2
(-7635 585);
DISPLAY 0.489362 (-7635 585);
PAINT MONO (-7635 585);
FORCEPROP 0 LASTPIN (-7625 525) $PN M73
J 2
(-7635 535);
DISPLAY 0.489362 (-7635 535);
PAINT MONO (-7635 535);
FORCEPROP 0 LASTPIN (-7625 475) $PN N1
J 2
(-7635 485);
DISPLAY 0.489362 (-7635 485);
PAINT MONO (-7635 485);
FORCEPROP 0 LASTPIN (-6525 6275) $PN N4
J 0
(-6515 6285);
DISPLAY 0.489362 (-6515 6285);
PAINT MONO (-6515 6285);
FORCEPROP 0 LASTPIN (-6525 6225) $PN N6
J 0
(-6515 6235);
DISPLAY 0.489362 (-6515 6235);
PAINT MONO (-6515 6235);
FORCEPROP 0 LASTPIN (-6525 6175) $PN N8
J 0
(-6515 6185);
DISPLAY 0.489362 (-6515 6185);
PAINT MONO (-6515 6185);
FORCEPROP 0 LASTPIN (-6525 6125) $PN N11
J 0
(-6515 6135);
DISPLAY 0.489362 (-6515 6135);
PAINT MONO (-6515 6135);
FORCEPROP 0 LASTPIN (-6525 6075) $PN N13
J 0
(-6515 6085);
DISPLAY 0.489362 (-6515 6085);
PAINT MONO (-6515 6085);
FORCEPROP 0 LASTPIN (-6525 6025) $PN N15
J 0
(-6515 6035);
DISPLAY 0.489362 (-6515 6035);
PAINT MONO (-6515 6035);
FORCEPROP 0 LASTPIN (-6525 5975) $PN N18
J 0
(-6515 5985);
DISPLAY 0.489362 (-6515 5985);
PAINT MONO (-6515 5985);
FORCEPROP 0 LASTPIN (-6525 5925) $PN N20
J 0
(-6515 5935);
DISPLAY 0.489362 (-6515 5935);
PAINT MONO (-6515 5935);
FORCEPROP 0 LASTPIN (-6525 5875) $PN N22
J 0
(-6515 5885);
DISPLAY 0.489362 (-6515 5885);
PAINT MONO (-6515 5885);
FORCEPROP 0 LASTPIN (-6525 5825) $PN N25
J 0
(-6515 5835);
DISPLAY 0.489362 (-6515 5835);
PAINT MONO (-6515 5835);
FORCEPROP 0 LASTPIN (-6525 5775) $PN N28
J 0
(-6515 5785);
DISPLAY 0.489362 (-6515 5785);
PAINT MONO (-6515 5785);
FORCEPROP 0 LASTPIN (-6525 5725) $PN N31
J 0
(-6515 5735);
DISPLAY 0.489362 (-6515 5735);
PAINT MONO (-6515 5735);
FORCEPROP 0 LASTPIN (-6525 5675) $PN N34
J 0
(-6515 5685);
DISPLAY 0.489362 (-6515 5685);
PAINT MONO (-6515 5685);
FORCEPROP 0 LASTPIN (-6525 5625) $PN N42
J 0
(-6515 5635);
DISPLAY 0.489362 (-6515 5635);
PAINT MONO (-6515 5635);
FORCEPROP 0 LASTPIN (-6525 5575) $PN N45
J 0
(-6515 5585);
DISPLAY 0.489362 (-6515 5585);
PAINT MONO (-6515 5585);
FORCEPROP 0 LASTPIN (-6525 5525) $PN N48
J 0
(-6515 5535);
DISPLAY 0.489362 (-6515 5535);
PAINT MONO (-6515 5535);
FORCEPROP 0 LASTPIN (-6525 5475) $PN N51
J 0
(-6515 5485);
DISPLAY 0.489362 (-6515 5485);
PAINT MONO (-6515 5485);
FORCEPROP 0 LASTPIN (-6525 5425) $PN N54
J 0
(-6515 5435);
DISPLAY 0.489362 (-6515 5435);
PAINT MONO (-6515 5435);
FORCEPROP 0 LASTPIN (-6525 5375) $PN N56
J 0
(-6515 5385);
DISPLAY 0.489362 (-6515 5385);
PAINT MONO (-6515 5385);
FORCEPROP 0 LASTPIN (-6525 5325) $PN N58
J 0
(-6515 5335);
DISPLAY 0.489362 (-6515 5335);
PAINT MONO (-6515 5335);
FORCEPROP 0 LASTPIN (-6525 5275) $PN N61
J 0
(-6515 5285);
DISPLAY 0.489362 (-6515 5285);
PAINT MONO (-6515 5285);
FORCEPROP 0 LASTPIN (-6525 5225) $PN N63
J 0
(-6515 5235);
DISPLAY 0.489362 (-6515 5235);
PAINT MONO (-6515 5235);
FORCEPROP 0 LASTPIN (-6525 5175) $PN N65
J 0
(-6515 5185);
DISPLAY 0.489362 (-6515 5185);
PAINT MONO (-6515 5185);
FORCEPROP 0 LASTPIN (-6525 5125) $PN N68
J 0
(-6515 5135);
DISPLAY 0.489362 (-6515 5135);
PAINT MONO (-6515 5135);
FORCEPROP 0 LASTPIN (-6525 5075) $PN N70
J 0
(-6515 5085);
DISPLAY 0.489362 (-6515 5085);
PAINT MONO (-6515 5085);
FORCEPROP 0 LASTPIN (-6525 5025) $PN N72
J 0
(-6515 5035);
DISPLAY 0.489362 (-6515 5035);
PAINT MONO (-6515 5035);
FORCEPROP 0 LASTPIN (-6525 4975) $PN N75
J 0
(-6515 4985);
DISPLAY 0.489362 (-6515 4985);
PAINT MONO (-6515 4985);
FORCEPROP 0 LASTPIN (-6525 4925) $PN P3
J 0
(-6515 4935);
DISPLAY 0.489362 (-6515 4935);
PAINT MONO (-6515 4935);
FORCEPROP 0 LASTPIN (-6525 4875) $PN P8
J 0
(-6515 4885);
DISPLAY 0.489362 (-6515 4885);
PAINT MONO (-6515 4885);
FORCEPROP 0 LASTPIN (-6525 4825) $PN P10
J 0
(-6515 4835);
DISPLAY 0.489362 (-6515 4835);
PAINT MONO (-6515 4835);
FORCEPROP 0 LASTPIN (-6525 4775) $PN P15
J 0
(-6515 4785);
DISPLAY 0.489362 (-6515 4785);
PAINT MONO (-6515 4785);
FORCEPROP 0 LASTPIN (-6525 4725) $PN P17
J 0
(-6515 4735);
DISPLAY 0.489362 (-6515 4735);
PAINT MONO (-6515 4735);
FORCEPROP 0 LASTPIN (-6525 4675) $PN P23
J 0
(-6515 4685);
DISPLAY 0.489362 (-6515 4685);
PAINT MONO (-6515 4685);
FORCEPROP 0 LASTPIN (-6525 4625) $PN P24
J 0
(-6515 4635);
DISPLAY 0.489362 (-6515 4635);
PAINT MONO (-6515 4635);
FORCEPROP 0 LASTPIN (-6525 4575) $PN P26
J 0
(-6515 4585);
DISPLAY 0.489362 (-6515 4585);
PAINT MONO (-6515 4585);
FORCEPROP 0 LASTPIN (-6525 4525) $PN P27
J 0
(-6515 4535);
DISPLAY 0.489362 (-6515 4535);
PAINT MONO (-6515 4535);
FORCEPROP 0 LASTPIN (-6525 4475) $PN P28
J 0
(-6515 4485);
DISPLAY 0.489362 (-6515 4485);
PAINT MONO (-6515 4485);
FORCEPROP 0 LASTPIN (-6525 4425) $PN P29
J 0
(-6515 4435);
DISPLAY 0.489362 (-6515 4435);
PAINT MONO (-6515 4435);
FORCEPROP 0 LASTPIN (-6525 4375) $PN P30
J 0
(-6515 4385);
DISPLAY 0.489362 (-6515 4385);
PAINT MONO (-6515 4385);
FORCEPROP 0 LASTPIN (-6525 4325) $PN P31
J 0
(-6515 4335);
DISPLAY 0.489362 (-6515 4335);
PAINT MONO (-6515 4335);
FORCEPROP 0 LASTPIN (-6525 4275) $PN P32
J 0
(-6515 4285);
DISPLAY 0.489362 (-6515 4285);
PAINT MONO (-6515 4285);
FORCEPROP 0 LASTPIN (-6525 4225) $PN P33
J 0
(-6515 4235);
DISPLAY 0.489362 (-6515 4235);
PAINT MONO (-6515 4235);
FORCEPROP 0 LASTPIN (-6525 4175) $PN P34
J 0
(-6515 4185);
DISPLAY 0.489362 (-6515 4185);
PAINT MONO (-6515 4185);
FORCEPROP 0 LASTPIN (-6525 4125) $PN P37
J 0
(-6515 4135);
DISPLAY 0.489362 (-6515 4135);
PAINT MONO (-6515 4135);
FORCEPROP 0 LASTPIN (-6525 4075) $PN P39
J 0
(-6515 4085);
DISPLAY 0.489362 (-6515 4085);
PAINT MONO (-6515 4085);
FORCEPROP 0 LASTPIN (-6525 4025) $PN P42
J 0
(-6515 4035);
DISPLAY 0.489362 (-6515 4035);
PAINT MONO (-6515 4035);
FORCEPROP 0 LASTPIN (-6525 3975) $PN P43
J 0
(-6515 3985);
DISPLAY 0.489362 (-6515 3985);
PAINT MONO (-6515 3985);
FORCEPROP 0 LASTPIN (-6525 3925) $PN P44
J 0
(-6515 3935);
DISPLAY 0.489362 (-6515 3935);
PAINT MONO (-6515 3935);
FORCEPROP 0 LASTPIN (-6525 3875) $PN P45
J 0
(-6515 3885);
DISPLAY 0.489362 (-6515 3885);
PAINT MONO (-6515 3885);
FORCEPROP 0 LASTPIN (-6525 3825) $PN P46
J 0
(-6515 3835);
DISPLAY 0.489362 (-6515 3835);
PAINT MONO (-6515 3835);
FORCEPROP 0 LASTPIN (-6525 3775) $PN P47
J 0
(-6515 3785);
DISPLAY 0.489362 (-6515 3785);
PAINT MONO (-6515 3785);
FORCEPROP 0 LASTPIN (-6525 3725) $PN P48
J 0
(-6515 3735);
DISPLAY 0.489362 (-6515 3735);
PAINT MONO (-6515 3735);
FORCEPROP 0 LASTPIN (-6525 3675) $PN P49
J 0
(-6515 3685);
DISPLAY 0.489362 (-6515 3685);
PAINT MONO (-6515 3685);
FORCEPROP 0 LASTPIN (-6525 3625) $PN P50
J 0
(-6515 3635);
DISPLAY 0.489362 (-6515 3635);
PAINT MONO (-6515 3635);
FORCEPROP 0 LASTPIN (-6525 3575) $PN P51
J 0
(-6515 3585);
DISPLAY 0.489362 (-6515 3585);
PAINT MONO (-6515 3585);
FORCEPROP 0 LASTPIN (-6525 3525) $PN P52
J 0
(-6515 3535);
DISPLAY 0.489362 (-6515 3535);
PAINT MONO (-6515 3535);
FORCEPROP 0 LASTPIN (-6525 3475) $PN P53
J 0
(-6515 3485);
DISPLAY 0.489362 (-6515 3485);
PAINT MONO (-6515 3485);
FORCEPROP 0 LASTPIN (-6525 3425) $PN P59
J 0
(-6515 3435);
DISPLAY 0.489362 (-6515 3435);
PAINT MONO (-6515 3435);
FORCEPROP 0 LASTPIN (-6525 3375) $PN P61
J 0
(-6515 3385);
DISPLAY 0.489362 (-6515 3385);
PAINT MONO (-6515 3385);
FORCEPROP 0 LASTPIN (-6525 3325) $PN P66
J 0
(-6515 3335);
DISPLAY 0.489362 (-6515 3335);
PAINT MONO (-6515 3335);
FORCEPROP 0 LASTPIN (-6525 3275) $PN P73
J 0
(-6515 3285);
DISPLAY 0.489362 (-6515 3285);
PAINT MONO (-6515 3285);
FORCEPROP 0 LASTPIN (-6525 3225) $PN R1
J 0
(-6515 3235);
DISPLAY 0.489362 (-6515 3235);
PAINT MONO (-6515 3235);
FORCEPROP 0 LASTPIN (-6525 3175) $PN R4
J 0
(-6515 3185);
DISPLAY 0.489362 (-6515 3185);
PAINT MONO (-6515 3185);
FORCEPROP 0 LASTPIN (-6525 3125) $PN R6
J 0
(-6515 3135);
DISPLAY 0.489362 (-6515 3135);
PAINT MONO (-6515 3135);
FORCEPROP 0 LASTPIN (-6525 3075) $PN R8
J 0
(-6515 3085);
DISPLAY 0.489362 (-6515 3085);
PAINT MONO (-6515 3085);
FORCEPROP 0 LASTPIN (-6525 3025) $PN R11
J 0
(-6515 3035);
DISPLAY 0.489362 (-6515 3035);
PAINT MONO (-6515 3035);
FORCEPROP 0 LASTPIN (-6525 2975) $PN R13
J 0
(-6515 2985);
DISPLAY 0.489362 (-6515 2985);
PAINT MONO (-6515 2985);
FORCEPROP 0 LASTPIN (-6525 2925) $PN R15
J 0
(-6515 2935);
DISPLAY 0.489362 (-6515 2935);
PAINT MONO (-6515 2935);
FORCEPROP 0 LASTPIN (-6525 2875) $PN R18
J 0
(-6515 2885);
DISPLAY 0.489362 (-6515 2885);
PAINT MONO (-6515 2885);
FORCEPROP 0 LASTPIN (-6525 2825) $PN R20
J 0
(-6515 2835);
DISPLAY 0.489362 (-6515 2835);
PAINT MONO (-6515 2835);
FORCEPROP 0 LASTPIN (-6525 2775) $PN R22
J 0
(-6515 2785);
DISPLAY 0.489362 (-6515 2785);
PAINT MONO (-6515 2785);
FORCEPROP 0 LASTPIN (-6525 2725) $PN R25
J 0
(-6515 2735);
DISPLAY 0.489362 (-6515 2735);
PAINT MONO (-6515 2735);
FORCEPROP 0 LASTPIN (-6525 2675) $PN R28
J 0
(-6515 2685);
DISPLAY 0.489362 (-6515 2685);
PAINT MONO (-6515 2685);
FORCEPROP 0 LASTPIN (-6525 2625) $PN R31
J 0
(-6515 2635);
DISPLAY 0.489362 (-6515 2635);
PAINT MONO (-6515 2635);
FORCEPROP 0 LASTPIN (-6525 2575) $PN R34
J 0
(-6515 2585);
DISPLAY 0.489362 (-6515 2585);
PAINT MONO (-6515 2585);
FORCEPROP 0 LASTPIN (-6525 2525) $PN R35
J 0
(-6515 2535);
DISPLAY 0.489362 (-6515 2535);
PAINT MONO (-6515 2535);
FORCEPROP 0 LASTPIN (-6525 2475) $PN R36
J 0
(-6515 2485);
DISPLAY 0.489362 (-6515 2485);
PAINT MONO (-6515 2485);
FORCEPROP 0 LASTPIN (-6525 2425) $PN R40
J 0
(-6515 2435);
DISPLAY 0.489362 (-6515 2435);
PAINT MONO (-6515 2435);
FORCEPROP 0 LASTPIN (-6525 2375) $PN R41
J 0
(-6515 2385);
DISPLAY 0.489362 (-6515 2385);
PAINT MONO (-6515 2385);
FORCEPROP 0 LASTPIN (-6525 2325) $PN R42
J 0
(-6515 2335);
DISPLAY 0.489362 (-6515 2335);
PAINT MONO (-6515 2335);
FORCEPROP 0 LASTPIN (-6525 2275) $PN R45
J 0
(-6515 2285);
DISPLAY 0.489362 (-6515 2285);
PAINT MONO (-6515 2285);
FORCEPROP 0 LASTPIN (-6525 2225) $PN R48
J 0
(-6515 2235);
DISPLAY 0.489362 (-6515 2235);
PAINT MONO (-6515 2235);
FORCEPROP 0 LASTPIN (-6525 2175) $PN R51
J 0
(-6515 2185);
DISPLAY 0.489362 (-6515 2185);
PAINT MONO (-6515 2185);
FORCEPROP 0 LASTPIN (-6525 2125) $PN R54
J 0
(-6515 2135);
DISPLAY 0.489362 (-6515 2135);
PAINT MONO (-6515 2135);
FORCEPROP 0 LASTPIN (-6525 2075) $PN R56
J 0
(-6515 2085);
DISPLAY 0.489362 (-6515 2085);
PAINT MONO (-6515 2085);
FORCEPROP 0 LASTPIN (-6525 2025) $PN R58
J 0
(-6515 2035);
DISPLAY 0.489362 (-6515 2035);
PAINT MONO (-6515 2035);
FORCEPROP 0 LASTPIN (-6525 1975) $PN R61
J 0
(-6515 1985);
DISPLAY 0.489362 (-6515 1985);
PAINT MONO (-6515 1985);
FORCEPROP 0 LASTPIN (-6525 1925) $PN R63
J 0
(-6515 1935);
DISPLAY 0.489362 (-6515 1935);
PAINT MONO (-6515 1935);
FORCEPROP 0 LASTPIN (-6525 1875) $PN R65
J 0
(-6515 1885);
DISPLAY 0.489362 (-6515 1885);
PAINT MONO (-6515 1885);
FORCEPROP 0 LASTPIN (-6525 1825) $PN R68
J 0
(-6515 1835);
DISPLAY 0.489362 (-6515 1835);
PAINT MONO (-6515 1835);
FORCEPROP 0 LASTPIN (-6525 1775) $PN R70
J 0
(-6515 1785);
DISPLAY 0.489362 (-6515 1785);
PAINT MONO (-6515 1785);
FORCEPROP 0 LASTPIN (-6525 1725) $PN R72
J 0
(-6515 1735);
DISPLAY 0.489362 (-6515 1735);
PAINT MONO (-6515 1735);
FORCEPROP 0 LASTPIN (-6525 1675) $PN R75
J 0
(-6515 1685);
DISPLAY 0.489362 (-6515 1685);
PAINT MONO (-6515 1685);
FORCEPROP 0 LASTPIN (-6525 1625) $PN T3
J 0
(-6515 1635);
DISPLAY 0.489362 (-6515 1635);
PAINT MONO (-6515 1635);
FORCEPROP 0 LASTPIN (-6525 1575) $PN T5
J 0
(-6515 1585);
DISPLAY 0.489362 (-6515 1585);
PAINT MONO (-6515 1585);
FORCEPROP 0 LASTPIN (-6525 1525) $PN T8
J 0
(-6515 1535);
DISPLAY 0.489362 (-6515 1535);
PAINT MONO (-6515 1535);
FORCEPROP 0 LASTPIN (-6525 1475) $PN T10
J 0
(-6515 1485);
DISPLAY 0.489362 (-6515 1485);
PAINT MONO (-6515 1485);
FORCEPROP 0 LASTPIN (-6525 1425) $PN T12
J 0
(-6515 1435);
DISPLAY 0.489362 (-6515 1435);
PAINT MONO (-6515 1435);
FORCEPROP 0 LASTPIN (-6525 1375) $PN T15
J 0
(-6515 1385);
DISPLAY 0.489362 (-6515 1385);
PAINT MONO (-6515 1385);
FORCEPROP 0 LASTPIN (-6525 1325) $PN T17
J 0
(-6515 1335);
DISPLAY 0.489362 (-6515 1335);
PAINT MONO (-6515 1335);
FORCEPROP 0 LASTPIN (-6525 1275) $PN T19
J 0
(-6515 1285);
DISPLAY 0.489362 (-6515 1285);
PAINT MONO (-6515 1285);
FORCEPROP 0 LASTPIN (-6525 1225) $PN T22
J 0
(-6515 1235);
DISPLAY 0.489362 (-6515 1235);
PAINT MONO (-6515 1235);
FORCEPROP 0 LASTPIN (-6525 1175) $PN T25
J 0
(-6515 1185);
DISPLAY 0.489362 (-6515 1185);
PAINT MONO (-6515 1185);
FORCEPROP 0 LASTPIN (-6525 1125) $PN T28
J 0
(-6515 1135);
DISPLAY 0.489362 (-6515 1135);
PAINT MONO (-6515 1135);
FORCEPROP 0 LASTPIN (-6525 1075) $PN T31
J 0
(-6515 1085);
DISPLAY 0.489362 (-6515 1085);
PAINT MONO (-6515 1085);
FORCEPROP 0 LASTPIN (-6525 1025) $PN T34
J 0
(-6515 1035);
DISPLAY 0.489362 (-6515 1035);
PAINT MONO (-6515 1035);
FORCEPROP 0 LASTPIN (-6525 975) $PN T37
J 0
(-6515 985);
DISPLAY 0.489362 (-6515 985);
PAINT MONO (-6515 985);
FORCEPROP 0 LASTPIN (-6525 925) $PN T39
J 0
(-6515 935);
DISPLAY 0.489362 (-6515 935);
PAINT MONO (-6515 935);
FORCEPROP 0 LASTPIN (-6525 875) $PN T42
J 0
(-6515 885);
DISPLAY 0.489362 (-6515 885);
PAINT MONO (-6515 885);
FORCEPROP 0 LASTPIN (-6525 825) $PN T45
J 0
(-6515 835);
DISPLAY 0.489362 (-6515 835);
PAINT MONO (-6515 835);
FORCEPROP 0 LASTPIN (-6525 775) $PN T48
J 0
(-6515 785);
DISPLAY 0.489362 (-6515 785);
PAINT MONO (-6515 785);
FORCEPROP 0 LASTPIN (-6525 725) $PN T51
J 0
(-6515 735);
DISPLAY 0.489362 (-6515 735);
PAINT MONO (-6515 735);
FORCEPROP 0 LASTPIN (-6525 675) $PN T54
J 0
(-6515 685);
DISPLAY 0.489362 (-6515 685);
PAINT MONO (-6515 685);
FORCEPROP 0 LASTPIN (-6525 625) $PN T57
J 0
(-6515 635);
DISPLAY 0.489362 (-6515 635);
PAINT MONO (-6515 635);
FORCEPROP 0 LASTPIN (-6525 575) $PN T59
J 0
(-6515 585);
DISPLAY 0.489362 (-6515 585);
PAINT MONO (-6515 585);
FORCEPROP 0 LASTPIN (-6525 525) $PN T61
J 0
(-6515 535);
DISPLAY 0.489362 (-6515 535);
PAINT MONO (-6515 535);
FORCEPROP 0 LASTPIN (-6525 475) $PN T64
J 0
(-6515 485);
DISPLAY 0.489362 (-6515 485);
PAINT MONO (-6515 485);
FORCEPROP 2 LAST PART_TYPE SMLF
J 0
(-7475 6700);
DISPLAY 1.021277 (-7475 6700);
FORCEPROP 1 LAST MATERIAL IO
J 0
(-7470 6507);
DISPLAY 0.489362 (-7470 6507);
PAINT SKYBLUE (-7470 6507);
FORCEPROP 2 LAST VALUE SOCKET6096_13568-001
J 0
(-7475 6555);
DISPLAY 0.489362 (-7475 6555);
PAINT SKYBLUE (-7475 6555);
FORCEPROP 1 LAST PART_NUMBER DGA^6000030
J 0
(-7470 6650);
DISPLAY 0.489362 (-7470 6650);
PAINT SKYBLUE (-7470 6650);
FORCEPROP 1 LAST NEEDS_NO_SIZE TRUE
J 0
(-7075 3425);
DISPLAY 0.723404 (-7075 3425);
PAINT GREEN (-7075 3425);
DISPLAY INVISIBLE (-7075 3425);
FORCEPROP 1 LAST CDS_LMAN_SYM_OUTLINE -400,3050,400,-3050
J 0
(-7075 3425);
DISPLAY 0.468085 (-7075 3425);
PAINT GREEN (-7075 3425);
DISPLAY INVISIBLE (-7075 3425);
FORCEPROP 2 LAST CDS_LIB pure_quanta
J 0
(-7075 3425);
DISPLAY INVISIBLE (-7075 3425);
FORCEPROP 1 LAST PATH I20
J 0
(-7075 3425);
DISPLAY 0.723404 (-7075 3425);
PAINT GREEN (-7075 3425);
DISPLAY INVISIBLE (-7075 3425);
FORCEADD GENOA_SP5..30
(-5600 3450);
FORCEPROP 1 LAST LOCATION U25
J 0
(-5995 6600);
DISPLAY 0.489362 (-5995 6600);
PAINT SKYBLUE (-5995 6600);
FORCEPROP 0 LAST $SEC 30
J 0
(-5975 6850);
DISPLAY 0.680851 (-5975 6850);
PAINT MONO (-5975 6850);
DISPLAY INVISIBLE (-5975 6850);
FORCEPROP 0 LAST CDS_SEC 30
J 0
(-6000 6725);
DISPLAY 1.021277 (-6000 6725);
DISPLAY INVISIBLE (-6000 6725);
FORCEPROP 0 LASTPIN (-5050 5600) $PN AA1
J 0
(-5040 5610);
DISPLAY 0.489362 (-5040 5610);
PAINT MONO (-5040 5610);
FORCEPROP 0 LASTPIN (-5050 5550) $PN AA4
J 0
(-5040 5560);
DISPLAY 0.489362 (-5040 5560);
PAINT MONO (-5040 5560);
FORCEPROP 0 LASTPIN (-5050 5500) $PN AA6
J 0
(-5040 5510);
DISPLAY 0.489362 (-5040 5510);
PAINT MONO (-5040 5510);
FORCEPROP 0 LASTPIN (-5050 5450) $PN AA8
J 0
(-5040 5460);
DISPLAY 0.489362 (-5040 5460);
PAINT MONO (-5040 5460);
FORCEPROP 0 LASTPIN (-5050 5400) $PN AA11
J 0
(-5040 5410);
DISPLAY 0.489362 (-5040 5410);
PAINT MONO (-5040 5410);
FORCEPROP 0 LASTPIN (-5050 5350) $PN AA13
J 0
(-5040 5360);
DISPLAY 0.489362 (-5040 5360);
PAINT MONO (-5040 5360);
FORCEPROP 0 LASTPIN (-5050 5300) $PN AA15
J 0
(-5040 5310);
DISPLAY 0.489362 (-5040 5310);
PAINT MONO (-5040 5310);
FORCEPROP 0 LASTPIN (-5050 5250) $PN AA18
J 0
(-5040 5260);
DISPLAY 0.489362 (-5040 5260);
PAINT MONO (-5040 5260);
FORCEPROP 0 LASTPIN (-5050 5200) $PN AA20
J 0
(-5040 5210);
DISPLAY 0.489362 (-5040 5210);
PAINT MONO (-5040 5210);
FORCEPROP 0 LASTPIN (-5050 5150) $PN AA31
J 0
(-5040 5160);
DISPLAY 0.489362 (-5040 5160);
PAINT MONO (-5040 5160);
FORCEPROP 0 LASTPIN (-5050 5100) $PN AA34
J 0
(-5040 5110);
DISPLAY 0.489362 (-5040 5110);
PAINT MONO (-5040 5110);
FORCEPROP 0 LASTPIN (-5050 5050) $PN AA35
J 0
(-5040 5060);
DISPLAY 0.489362 (-5040 5060);
PAINT MONO (-5040 5060);
FORCEPROP 0 LASTPIN (-5050 5000) $PN AA36
J 0
(-5040 5010);
DISPLAY 0.489362 (-5040 5010);
PAINT MONO (-5040 5010);
FORCEPROP 0 LASTPIN (-5050 4950) $PN AA40
J 0
(-5040 4960);
DISPLAY 0.489362 (-5040 4960);
PAINT MONO (-5040 4960);
FORCEPROP 0 LASTPIN (-5050 4900) $PN AA41
J 0
(-5040 4910);
DISPLAY 0.489362 (-5040 4910);
PAINT MONO (-5040 4910);
FORCEPROP 0 LASTPIN (-5050 4850) $PN AA45
J 0
(-5040 4860);
DISPLAY 0.489362 (-5040 4860);
PAINT MONO (-5040 4860);
FORCEPROP 0 LASTPIN (-5050 4800) $PN AA56
J 0
(-5040 4810);
DISPLAY 0.489362 (-5040 4810);
PAINT MONO (-5040 4810);
FORCEPROP 0 LASTPIN (-5050 4750) $PN AA58
J 0
(-5040 4760);
DISPLAY 0.489362 (-5040 4760);
PAINT MONO (-5040 4760);
FORCEPROP 0 LASTPIN (-5050 4700) $PN AA61
J 0
(-5040 4710);
DISPLAY 0.489362 (-5040 4710);
PAINT MONO (-5040 4710);
FORCEPROP 0 LASTPIN (-5050 4650) $PN AA63
J 0
(-5040 4660);
DISPLAY 0.489362 (-5040 4660);
PAINT MONO (-5040 4660);
FORCEPROP 0 LASTPIN (-5050 4600) $PN AA65
J 0
(-5040 4610);
DISPLAY 0.489362 (-5040 4610);
PAINT MONO (-5040 4610);
FORCEPROP 0 LASTPIN (-5050 4550) $PN AA68
J 0
(-5040 4560);
DISPLAY 0.489362 (-5040 4560);
PAINT MONO (-5040 4560);
FORCEPROP 0 LASTPIN (-5050 4500) $PN AA70
J 0
(-5040 4510);
DISPLAY 0.489362 (-5040 4510);
PAINT MONO (-5040 4510);
FORCEPROP 0 LASTPIN (-5050 4450) $PN AA75
J 0
(-5040 4460);
DISPLAY 0.489362 (-5040 4460);
PAINT MONO (-5040 4460);
FORCEPROP 0 LASTPIN (-5050 4400) $PN AB3
J 0
(-5040 4410);
DISPLAY 0.489362 (-5040 4410);
PAINT MONO (-5040 4410);
FORCEPROP 0 LASTPIN (-5050 4350) $PN AB5
J 0
(-5040 4360);
DISPLAY 0.489362 (-5040 4360);
PAINT MONO (-5040 4360);
FORCEPROP 0 LASTPIN (-5050 4300) $PN AB8
J 0
(-5040 4310);
DISPLAY 0.489362 (-5040 4310);
PAINT MONO (-5040 4310);
FORCEPROP 0 LASTPIN (-5050 4250) $PN AB10
J 0
(-5040 4260);
DISPLAY 0.489362 (-5040 4260);
PAINT MONO (-5040 4260);
FORCEPROP 0 LASTPIN (-5050 4200) $PN AB12
J 0
(-5040 4210);
DISPLAY 0.489362 (-5040 4210);
PAINT MONO (-5040 4210);
FORCEPROP 0 LASTPIN (-5050 4150) $PN AB15
J 0
(-5040 4160);
DISPLAY 0.489362 (-5040 4160);
PAINT MONO (-5040 4160);
FORCEPROP 0 LASTPIN (-5050 4100) $PN AB17
J 0
(-5040 4110);
DISPLAY 0.489362 (-5040 4110);
PAINT MONO (-5040 4110);
FORCEPROP 0 LASTPIN (-5050 4050) $PN AB19
J 0
(-5040 4060);
DISPLAY 0.489362 (-5040 4060);
PAINT MONO (-5040 4060);
FORCEPROP 0 LASTPIN (-5050 4000) $PN AB22
J 0
(-5040 4010);
DISPLAY 0.489362 (-5040 4010);
PAINT MONO (-5040 4010);
FORCEPROP 0 LASTPIN (-5050 3950) $PN AB25
J 0
(-5040 3960);
DISPLAY 0.489362 (-5040 3960);
PAINT MONO (-5040 3960);
FORCEPROP 0 LASTPIN (-5050 3900) $PN AB28
J 0
(-5040 3910);
DISPLAY 0.489362 (-5040 3910);
PAINT MONO (-5040 3910);
FORCEPROP 0 LASTPIN (-5050 3850) $PN AB31
J 0
(-5040 3860);
DISPLAY 0.489362 (-5040 3860);
PAINT MONO (-5040 3860);
FORCEPROP 0 LASTPIN (-5050 3800) $PN AB34
J 0
(-5040 3810);
DISPLAY 0.489362 (-5040 3810);
PAINT MONO (-5040 3810);
FORCEPROP 0 LASTPIN (-5050 3750) $PN AB37
J 0
(-5040 3760);
DISPLAY 0.489362 (-5040 3760);
PAINT MONO (-5040 3760);
FORCEPROP 0 LASTPIN (-5050 3700) $PN AB39
J 0
(-5040 3710);
DISPLAY 0.489362 (-5040 3710);
PAINT MONO (-5040 3710);
FORCEPROP 0 LASTPIN (-5050 3650) $PN AB42
J 0
(-5040 3660);
DISPLAY 0.489362 (-5040 3660);
PAINT MONO (-5040 3660);
FORCEPROP 0 LASTPIN (-5050 3600) $PN AB45
J 0
(-5040 3610);
DISPLAY 0.489362 (-5040 3610);
PAINT MONO (-5040 3610);
FORCEPROP 0 LASTPIN (-5050 3550) $PN AB48
J 0
(-5040 3560);
DISPLAY 0.489362 (-5040 3560);
PAINT MONO (-5040 3560);
FORCEPROP 0 LASTPIN (-5050 3500) $PN AB51
J 0
(-5040 3510);
DISPLAY 0.489362 (-5040 3510);
PAINT MONO (-5040 3510);
FORCEPROP 0 LASTPIN (-5050 3450) $PN AB54
J 0
(-5040 3460);
DISPLAY 0.489362 (-5040 3460);
PAINT MONO (-5040 3460);
FORCEPROP 0 LASTPIN (-5050 3400) $PN AB57
J 0
(-5040 3410);
DISPLAY 0.489362 (-5040 3410);
PAINT MONO (-5040 3410);
FORCEPROP 0 LASTPIN (-5050 3350) $PN AB59
J 0
(-5040 3360);
DISPLAY 0.489362 (-5040 3360);
PAINT MONO (-5040 3360);
FORCEPROP 0 LASTPIN (-5050 3300) $PN AB61
J 0
(-5040 3310);
DISPLAY 0.489362 (-5040 3310);
PAINT MONO (-5040 3310);
FORCEPROP 0 LASTPIN (-5050 3250) $PN AB64
J 0
(-5040 3260);
DISPLAY 0.489362 (-5040 3260);
PAINT MONO (-5040 3260);
FORCEPROP 0 LASTPIN (-5050 3200) $PN AB66
J 0
(-5040 3210);
DISPLAY 0.489362 (-5040 3210);
PAINT MONO (-5040 3210);
FORCEPROP 0 LASTPIN (-5050 3150) $PN AB68
J 0
(-5040 3160);
DISPLAY 0.489362 (-5040 3160);
PAINT MONO (-5040 3160);
FORCEPROP 0 LASTPIN (-5050 3100) $PN AB71
J 0
(-5040 3110);
DISPLAY 0.489362 (-5040 3110);
PAINT MONO (-5040 3110);
FORCEPROP 0 LASTPIN (-5050 3050) $PN AB73
J 0
(-5040 3060);
DISPLAY 0.489362 (-5040 3060);
PAINT MONO (-5040 3060);
FORCEPROP 0 LASTPIN (-5050 3000) $PN AC1
J 0
(-5040 3010);
DISPLAY 0.489362 (-5040 3010);
PAINT MONO (-5040 3010);
FORCEPROP 0 LASTPIN (-5050 2950) $PN AC6
J 0
(-5040 2960);
DISPLAY 0.489362 (-5040 2960);
PAINT MONO (-5040 2960);
FORCEPROP 0 LASTPIN (-5050 2900) $PN AC8
J 0
(-5040 2910);
DISPLAY 0.489362 (-5040 2910);
PAINT MONO (-5040 2910);
FORCEPROP 0 LASTPIN (-5050 2850) $PN AC13
J 0
(-5040 2860);
DISPLAY 0.489362 (-5040 2860);
PAINT MONO (-5040 2860);
FORCEPROP 0 LASTPIN (-5050 2800) $PN AC15
J 0
(-5040 2810);
DISPLAY 0.489362 (-5040 2810);
PAINT MONO (-5040 2810);
FORCEPROP 0 LASTPIN (-5050 2750) $PN AC20
J 0
(-5040 2760);
DISPLAY 0.489362 (-5040 2760);
PAINT MONO (-5040 2760);
FORCEPROP 0 LASTPIN (-5050 2700) $PN AC22
J 0
(-5040 2710);
DISPLAY 0.489362 (-5040 2710);
PAINT MONO (-5040 2710);
FORCEPROP 0 LASTPIN (-5050 2650) $PN AC25
J 0
(-5040 2660);
DISPLAY 0.489362 (-5040 2660);
PAINT MONO (-5040 2660);
FORCEPROP 0 LASTPIN (-5050 2600) $PN AC28
J 0
(-5040 2610);
DISPLAY 0.489362 (-5040 2610);
PAINT MONO (-5040 2610);
FORCEPROP 0 LASTPIN (-5050 2550) $PN AC31
J 0
(-5040 2560);
DISPLAY 0.489362 (-5040 2560);
PAINT MONO (-5040 2560);
FORCEPROP 0 LASTPIN (-5050 2500) $PN AC34
J 0
(-5040 2510);
DISPLAY 0.489362 (-5040 2510);
PAINT MONO (-5040 2510);
FORCEPROP 0 LASTPIN (-5050 2450) $PN AC42
J 0
(-5040 2460);
DISPLAY 0.489362 (-5040 2460);
PAINT MONO (-5040 2460);
FORCEPROP 0 LASTPIN (-5050 2400) $PN AC45
J 0
(-5040 2410);
DISPLAY 0.489362 (-5040 2410);
PAINT MONO (-5040 2410);
FORCEPROP 0 LASTPIN (-5050 2350) $PN AC48
J 0
(-5040 2360);
DISPLAY 0.489362 (-5040 2360);
PAINT MONO (-5040 2360);
FORCEPROP 0 LASTPIN (-5050 2300) $PN AC51
J 0
(-5040 2310);
DISPLAY 0.489362 (-5040 2310);
PAINT MONO (-5040 2310);
FORCEPROP 0 LASTPIN (-5050 2250) $PN AC54
J 0
(-5040 2260);
DISPLAY 0.489362 (-5040 2260);
PAINT MONO (-5040 2260);
FORCEPROP 0 LASTPIN (-5050 2200) $PN AC56
J 0
(-5040 2210);
DISPLAY 0.489362 (-5040 2210);
PAINT MONO (-5040 2210);
FORCEPROP 0 LASTPIN (-5050 2150) $PN AC61
J 0
(-5040 2160);
DISPLAY 0.489362 (-5040 2160);
PAINT MONO (-5040 2160);
FORCEPROP 0 LASTPIN (-5050 2100) $PN AC63
J 0
(-5040 2110);
DISPLAY 0.489362 (-5040 2110);
PAINT MONO (-5040 2110);
FORCEPROP 0 LASTPIN (-5050 2050) $PN AC68
J 0
(-5040 2060);
DISPLAY 0.489362 (-5040 2060);
PAINT MONO (-5040 2060);
FORCEPROP 0 LASTPIN (-5050 2000) $PN AC70
J 0
(-5040 2010);
DISPLAY 0.489362 (-5040 2010);
PAINT MONO (-5040 2010);
FORCEPROP 0 LASTPIN (-5050 1950) $PN AC75
J 0
(-5040 1960);
DISPLAY 0.489362 (-5040 1960);
PAINT MONO (-5040 1960);
FORCEPROP 0 LASTPIN (-5050 1900) $PN AD3
J 0
(-5040 1910);
DISPLAY 0.489362 (-5040 1910);
PAINT MONO (-5040 1910);
FORCEPROP 0 LASTPIN (-5050 1850) $PN AD5
J 0
(-5040 1860);
DISPLAY 0.489362 (-5040 1860);
PAINT MONO (-5040 1860);
FORCEPROP 0 LASTPIN (-5050 1800) $PN AD8
J 0
(-5040 1810);
DISPLAY 0.489362 (-5040 1810);
PAINT MONO (-5040 1810);
FORCEPROP 0 LASTPIN (-5050 1750) $PN AD10
J 0
(-5040 1760);
DISPLAY 0.489362 (-5040 1760);
PAINT MONO (-5040 1760);
FORCEPROP 0 LASTPIN (-5050 1700) $PN AD12
J 0
(-5040 1710);
DISPLAY 0.489362 (-5040 1710);
PAINT MONO (-5040 1710);
FORCEPROP 0 LASTPIN (-5050 1650) $PN AD15
J 0
(-5040 1660);
DISPLAY 0.489362 (-5040 1660);
PAINT MONO (-5040 1660);
FORCEPROP 0 LASTPIN (-5050 1600) $PN AD17
J 0
(-5040 1610);
DISPLAY 0.489362 (-5040 1610);
PAINT MONO (-5040 1610);
FORCEPROP 0 LASTPIN (-5050 1550) $PN AD19
J 0
(-5040 1560);
DISPLAY 0.489362 (-5040 1560);
PAINT MONO (-5040 1560);
FORCEPROP 0 LASTPIN (-5050 1500) $PN AD23
J 0
(-5040 1510);
DISPLAY 0.489362 (-5040 1510);
PAINT MONO (-5040 1510);
FORCEPROP 0 LASTPIN (-5050 1450) $PN AD24
J 0
(-5040 1460);
DISPLAY 0.489362 (-5040 1460);
PAINT MONO (-5040 1460);
FORCEPROP 0 LASTPIN (-5050 1400) $PN AD25
J 0
(-5040 1410);
DISPLAY 0.489362 (-5040 1410);
PAINT MONO (-5040 1410);
FORCEPROP 0 LASTPIN (-5050 1350) $PN AD26
J 0
(-5040 1360);
DISPLAY 0.489362 (-5040 1360);
PAINT MONO (-5040 1360);
FORCEPROP 0 LASTPIN (-5050 1300) $PN AD27
J 0
(-5040 1310);
DISPLAY 0.489362 (-5040 1310);
PAINT MONO (-5040 1310);
FORCEPROP 0 LASTPIN (-5050 1250) $PN AD28
J 0
(-5040 1260);
DISPLAY 0.489362 (-5040 1260);
PAINT MONO (-5040 1260);
FORCEPROP 0 LASTPIN (-5050 1200) $PN AD29
J 0
(-5040 1210);
DISPLAY 0.489362 (-5040 1210);
PAINT MONO (-5040 1210);
FORCEPROP 0 LASTPIN (-5050 1150) $PN AD30
J 0
(-5040 1160);
DISPLAY 0.489362 (-5040 1160);
PAINT MONO (-5040 1160);
FORCEPROP 0 LASTPIN (-5050 1100) $PN AD32
J 0
(-5040 1110);
DISPLAY 0.489362 (-5040 1110);
PAINT MONO (-5040 1110);
FORCEPROP 0 LASTPIN (-5050 1050) $PN AD33
J 0
(-5040 1060);
DISPLAY 0.489362 (-5040 1060);
PAINT MONO (-5040 1060);
FORCEPROP 0 LASTPIN (-5050 1000) $PN AD34
J 0
(-5040 1010);
DISPLAY 0.489362 (-5040 1010);
PAINT MONO (-5040 1010);
FORCEPROP 0 LASTPIN (-5050 950) $PN AD37
J 0
(-5040 960);
DISPLAY 0.489362 (-5040 960);
PAINT MONO (-5040 960);
FORCEPROP 0 LASTPIN (-5050 900) $PN AD39
J 0
(-5040 910);
DISPLAY 0.489362 (-5040 910);
PAINT MONO (-5040 910);
FORCEPROP 0 LASTPIN (-5050 850) $PN AD42
J 0
(-5040 860);
DISPLAY 0.489362 (-5040 860);
PAINT MONO (-5040 860);
FORCEPROP 0 LASTPIN (-5050 800) $PN AD43
J 0
(-5040 810);
DISPLAY 0.489362 (-5040 810);
PAINT MONO (-5040 810);
FORCEPROP 0 LASTPIN (-5050 750) $PN AD44
J 0
(-5040 760);
DISPLAY 0.489362 (-5040 760);
PAINT MONO (-5040 760);
FORCEPROP 0 LASTPIN (-5050 700) $PN AD45
J 0
(-5040 710);
DISPLAY 0.489362 (-5040 710);
PAINT MONO (-5040 710);
FORCEPROP 0 LASTPIN (-5050 650) $PN AD46
J 0
(-5040 660);
DISPLAY 0.489362 (-5040 660);
PAINT MONO (-5040 660);
FORCEPROP 0 LASTPIN (-5050 600) $PN AD47
J 0
(-5040 610);
DISPLAY 0.489362 (-5040 610);
PAINT MONO (-5040 610);
FORCEPROP 0 LASTPIN (-5050 550) $PN AD48
J 0
(-5040 560);
DISPLAY 0.489362 (-5040 560);
PAINT MONO (-5040 560);
FORCEPROP 0 LASTPIN (-6150 6300) $PN T66
J 2
(-6160 6310);
DISPLAY 0.489362 (-6160 6310);
PAINT MONO (-6160 6310);
FORCEPROP 0 LASTPIN (-6150 6250) $PN T68
J 2
(-6160 6260);
DISPLAY 0.489362 (-6160 6260);
PAINT MONO (-6160 6260);
FORCEPROP 0 LASTPIN (-6150 6200) $PN T71
J 2
(-6160 6210);
DISPLAY 0.489362 (-6160 6210);
PAINT MONO (-6160 6210);
FORCEPROP 0 LASTPIN (-6150 6150) $PN T73
J 2
(-6160 6160);
DISPLAY 0.489362 (-6160 6160);
PAINT MONO (-6160 6160);
FORCEPROP 0 LASTPIN (-6150 6100) $PN U1
J 2
(-6160 6110);
DISPLAY 0.489362 (-6160 6110);
PAINT MONO (-6160 6110);
FORCEPROP 0 LASTPIN (-6150 6050) $PN U6
J 2
(-6160 6060);
DISPLAY 0.489362 (-6160 6060);
PAINT MONO (-6160 6060);
FORCEPROP 0 LASTPIN (-6150 6000) $PN U8
J 2
(-6160 6010);
DISPLAY 0.489362 (-6160 6010);
PAINT MONO (-6160 6010);
FORCEPROP 0 LASTPIN (-6150 5950) $PN U13
J 2
(-6160 5960);
DISPLAY 0.489362 (-6160 5960);
PAINT MONO (-6160 5960);
FORCEPROP 0 LASTPIN (-6150 5900) $PN U15
J 2
(-6160 5910);
DISPLAY 0.489362 (-6160 5910);
PAINT MONO (-6160 5910);
FORCEPROP 0 LASTPIN (-6150 5850) $PN U20
J 2
(-6160 5860);
DISPLAY 0.489362 (-6160 5860);
PAINT MONO (-6160 5860);
FORCEPROP 0 LASTPIN (-6150 5800) $PN U22
J 2
(-6160 5810);
DISPLAY 0.489362 (-6160 5810);
PAINT MONO (-6160 5810);
FORCEPROP 0 LASTPIN (-6150 5750) $PN U25
J 2
(-6160 5760);
DISPLAY 0.489362 (-6160 5760);
PAINT MONO (-6160 5760);
FORCEPROP 0 LASTPIN (-6150 5700) $PN U28
J 2
(-6160 5710);
DISPLAY 0.489362 (-6160 5710);
PAINT MONO (-6160 5710);
FORCEPROP 0 LASTPIN (-6150 5650) $PN U31
J 2
(-6160 5660);
DISPLAY 0.489362 (-6160 5660);
PAINT MONO (-6160 5660);
FORCEPROP 0 LASTPIN (-6150 5600) $PN U34
J 2
(-6160 5610);
DISPLAY 0.489362 (-6160 5610);
PAINT MONO (-6160 5610);
FORCEPROP 0 LASTPIN (-6150 5550) $PN U42
J 2
(-6160 5560);
DISPLAY 0.489362 (-6160 5560);
PAINT MONO (-6160 5560);
FORCEPROP 0 LASTPIN (-6150 5500) $PN U45
J 2
(-6160 5510);
DISPLAY 0.489362 (-6160 5510);
PAINT MONO (-6160 5510);
FORCEPROP 0 LASTPIN (-6150 5450) $PN U48
J 2
(-6160 5460);
DISPLAY 0.489362 (-6160 5460);
PAINT MONO (-6160 5460);
FORCEPROP 0 LASTPIN (-6150 5400) $PN U51
J 2
(-6160 5410);
DISPLAY 0.489362 (-6160 5410);
PAINT MONO (-6160 5410);
FORCEPROP 0 LASTPIN (-6150 5350) $PN U54
J 2
(-6160 5360);
DISPLAY 0.489362 (-6160 5360);
PAINT MONO (-6160 5360);
FORCEPROP 0 LASTPIN (-6150 5300) $PN U56
J 2
(-6160 5310);
DISPLAY 0.489362 (-6160 5310);
PAINT MONO (-6160 5310);
FORCEPROP 0 LASTPIN (-6150 5250) $PN U61
J 2
(-6160 5260);
DISPLAY 0.489362 (-6160 5260);
PAINT MONO (-6160 5260);
FORCEPROP 0 LASTPIN (-6150 5200) $PN U63
J 2
(-6160 5210);
DISPLAY 0.489362 (-6160 5210);
PAINT MONO (-6160 5210);
FORCEPROP 0 LASTPIN (-6150 5150) $PN U68
J 2
(-6160 5160);
DISPLAY 0.489362 (-6160 5160);
PAINT MONO (-6160 5160);
FORCEPROP 0 LASTPIN (-6150 5100) $PN U70
J 2
(-6160 5110);
DISPLAY 0.489362 (-6160 5110);
PAINT MONO (-6160 5110);
FORCEPROP 0 LASTPIN (-6150 5050) $PN U75
J 2
(-6160 5060);
DISPLAY 0.489362 (-6160 5060);
PAINT MONO (-6160 5060);
FORCEPROP 0 LASTPIN (-6150 5000) $PN V3
J 2
(-6160 5010);
DISPLAY 0.489362 (-6160 5010);
PAINT MONO (-6160 5010);
FORCEPROP 0 LASTPIN (-6150 4950) $PN V5
J 2
(-6160 4960);
DISPLAY 0.489362 (-6160 4960);
PAINT MONO (-6160 4960);
FORCEPROP 0 LASTPIN (-6150 4900) $PN V8
J 2
(-6160 4910);
DISPLAY 0.489362 (-6160 4910);
PAINT MONO (-6160 4910);
FORCEPROP 0 LASTPIN (-6150 4850) $PN V10
J 2
(-6160 4860);
DISPLAY 0.489362 (-6160 4860);
PAINT MONO (-6160 4860);
FORCEPROP 0 LASTPIN (-6150 4800) $PN V12
J 2
(-6160 4810);
DISPLAY 0.489362 (-6160 4810);
PAINT MONO (-6160 4810);
FORCEPROP 0 LASTPIN (-6150 4750) $PN V15
J 2
(-6160 4760);
DISPLAY 0.489362 (-6160 4760);
PAINT MONO (-6160 4760);
FORCEPROP 0 LASTPIN (-6150 4700) $PN V17
J 2
(-6160 4710);
DISPLAY 0.489362 (-6160 4710);
PAINT MONO (-6160 4710);
FORCEPROP 0 LASTPIN (-6150 4650) $PN V19
J 2
(-6160 4660);
DISPLAY 0.489362 (-6160 4660);
PAINT MONO (-6160 4660);
FORCEPROP 0 LASTPIN (-6150 4600) $PN V23
J 2
(-6160 4610);
DISPLAY 0.489362 (-6160 4610);
PAINT MONO (-6160 4610);
FORCEPROP 0 LASTPIN (-6150 4550) $PN V24
J 2
(-6160 4560);
DISPLAY 0.489362 (-6160 4560);
PAINT MONO (-6160 4560);
FORCEPROP 0 LASTPIN (-6150 4500) $PN V25
J 2
(-6160 4510);
DISPLAY 0.489362 (-6160 4510);
PAINT MONO (-6160 4510);
FORCEPROP 0 LASTPIN (-6150 4450) $PN V26
J 2
(-6160 4460);
DISPLAY 0.489362 (-6160 4460);
PAINT MONO (-6160 4460);
FORCEPROP 0 LASTPIN (-6150 4400) $PN V28
J 2
(-6160 4410);
DISPLAY 0.489362 (-6160 4410);
PAINT MONO (-6160 4410);
FORCEPROP 0 LASTPIN (-6150 4350) $PN V29
J 2
(-6160 4360);
DISPLAY 0.489362 (-6160 4360);
PAINT MONO (-6160 4360);
FORCEPROP 0 LASTPIN (-6150 4300) $PN V30
J 2
(-6160 4310);
DISPLAY 0.489362 (-6160 4310);
PAINT MONO (-6160 4310);
FORCEPROP 0 LASTPIN (-6150 4250) $PN V31
J 2
(-6160 4260);
DISPLAY 0.489362 (-6160 4260);
PAINT MONO (-6160 4260);
FORCEPROP 0 LASTPIN (-6150 4200) $PN V32
J 2
(-6160 4210);
DISPLAY 0.489362 (-6160 4210);
PAINT MONO (-6160 4210);
FORCEPROP 0 LASTPIN (-6150 4150) $PN V33
J 2
(-6160 4160);
DISPLAY 0.489362 (-6160 4160);
PAINT MONO (-6160 4160);
FORCEPROP 0 LASTPIN (-6150 4100) $PN V34
J 2
(-6160 4110);
DISPLAY 0.489362 (-6160 4110);
PAINT MONO (-6160 4110);
FORCEPROP 0 LASTPIN (-6150 4050) $PN V37
J 2
(-6160 4060);
DISPLAY 0.489362 (-6160 4060);
PAINT MONO (-6160 4060);
FORCEPROP 0 LASTPIN (-6150 4000) $PN V39
J 2
(-6160 4010);
DISPLAY 0.489362 (-6160 4010);
PAINT MONO (-6160 4010);
FORCEPROP 0 LASTPIN (-6150 3950) $PN V42
J 2
(-6160 3960);
DISPLAY 0.489362 (-6160 3960);
PAINT MONO (-6160 3960);
FORCEPROP 0 LASTPIN (-6150 3900) $PN V43
J 2
(-6160 3910);
DISPLAY 0.489362 (-6160 3910);
PAINT MONO (-6160 3910);
FORCEPROP 0 LASTPIN (-6150 3850) $PN V44
J 2
(-6160 3860);
DISPLAY 0.489362 (-6160 3860);
PAINT MONO (-6160 3860);
FORCEPROP 0 LASTPIN (-6150 3800) $PN V45
J 2
(-6160 3810);
DISPLAY 0.489362 (-6160 3810);
PAINT MONO (-6160 3810);
FORCEPROP 0 LASTPIN (-6150 3750) $PN V46
J 2
(-6160 3760);
DISPLAY 0.489362 (-6160 3760);
PAINT MONO (-6160 3760);
FORCEPROP 0 LASTPIN (-6150 3700) $PN V47
J 2
(-6160 3710);
DISPLAY 0.489362 (-6160 3710);
PAINT MONO (-6160 3710);
FORCEPROP 0 LASTPIN (-6150 3650) $PN V48
J 2
(-6160 3660);
DISPLAY 0.489362 (-6160 3660);
PAINT MONO (-6160 3660);
FORCEPROP 0 LASTPIN (-6150 3600) $PN V49
J 2
(-6160 3610);
DISPLAY 0.489362 (-6160 3610);
PAINT MONO (-6160 3610);
FORCEPROP 0 LASTPIN (-6150 3550) $PN V50
J 2
(-6160 3560);
DISPLAY 0.489362 (-6160 3560);
PAINT MONO (-6160 3560);
FORCEPROP 0 LASTPIN (-6150 3500) $PN V51
J 2
(-6160 3510);
DISPLAY 0.489362 (-6160 3510);
PAINT MONO (-6160 3510);
FORCEPROP 0 LASTPIN (-6150 3450) $PN V52
J 2
(-6160 3460);
DISPLAY 0.489362 (-6160 3460);
PAINT MONO (-6160 3460);
FORCEPROP 0 LASTPIN (-6150 3400) $PN V53
J 2
(-6160 3410);
DISPLAY 0.489362 (-6160 3410);
PAINT MONO (-6160 3410);
FORCEPROP 0 LASTPIN (-6150 3350) $PN V57
J 2
(-6160 3360);
DISPLAY 0.489362 (-6160 3360);
PAINT MONO (-6160 3360);
FORCEPROP 0 LASTPIN (-6150 3300) $PN V59
J 2
(-6160 3310);
DISPLAY 0.489362 (-6160 3310);
PAINT MONO (-6160 3310);
FORCEPROP 0 LASTPIN (-6150 3250) $PN V61
J 2
(-6160 3260);
DISPLAY 0.489362 (-6160 3260);
PAINT MONO (-6160 3260);
FORCEPROP 0 LASTPIN (-6150 3200) $PN V64
J 2
(-6160 3210);
DISPLAY 0.489362 (-6160 3210);
PAINT MONO (-6160 3210);
FORCEPROP 0 LASTPIN (-6150 3150) $PN V66
J 2
(-6160 3160);
DISPLAY 0.489362 (-6160 3160);
PAINT MONO (-6160 3160);
FORCEPROP 0 LASTPIN (-6150 3100) $PN V71
J 2
(-6160 3110);
DISPLAY 0.489362 (-6160 3110);
PAINT MONO (-6160 3110);
FORCEPROP 0 LASTPIN (-6150 3050) $PN V73
J 2
(-6160 3060);
DISPLAY 0.489362 (-6160 3060);
PAINT MONO (-6160 3060);
FORCEPROP 0 LASTPIN (-6150 3000) $PN W1
J 2
(-6160 3010);
DISPLAY 0.489362 (-6160 3010);
PAINT MONO (-6160 3010);
FORCEPROP 0 LASTPIN (-6150 2950) $PN W4
J 2
(-6160 2960);
DISPLAY 0.489362 (-6160 2960);
PAINT MONO (-6160 2960);
FORCEPROP 0 LASTPIN (-6150 2900) $PN W6
J 2
(-6160 2910);
DISPLAY 0.489362 (-6160 2910);
PAINT MONO (-6160 2910);
FORCEPROP 0 LASTPIN (-6150 2850) $PN W8
J 2
(-6160 2860);
DISPLAY 0.489362 (-6160 2860);
PAINT MONO (-6160 2860);
FORCEPROP 0 LASTPIN (-6150 2800) $PN W11
J 2
(-6160 2810);
DISPLAY 0.489362 (-6160 2810);
PAINT MONO (-6160 2810);
FORCEPROP 0 LASTPIN (-6150 2750) $PN W13
J 2
(-6160 2760);
DISPLAY 0.489362 (-6160 2760);
PAINT MONO (-6160 2760);
FORCEPROP 0 LASTPIN (-6150 2700) $PN W15
J 2
(-6160 2710);
DISPLAY 0.489362 (-6160 2710);
PAINT MONO (-6160 2710);
FORCEPROP 0 LASTPIN (-6150 2650) $PN W18
J 2
(-6160 2660);
DISPLAY 0.489362 (-6160 2660);
PAINT MONO (-6160 2660);
FORCEPROP 0 LASTPIN (-6150 2600) $PN W20
J 2
(-6160 2610);
DISPLAY 0.489362 (-6160 2610);
PAINT MONO (-6160 2610);
FORCEPROP 0 LASTPIN (-6150 2550) $PN W22
J 2
(-6160 2560);
DISPLAY 0.489362 (-6160 2560);
PAINT MONO (-6160 2560);
FORCEPROP 0 LASTPIN (-6150 2500) $PN W25
J 2
(-6160 2510);
DISPLAY 0.489362 (-6160 2510);
PAINT MONO (-6160 2510);
FORCEPROP 0 LASTPIN (-6150 2450) $PN W28
J 2
(-6160 2460);
DISPLAY 0.489362 (-6160 2460);
PAINT MONO (-6160 2460);
FORCEPROP 0 LASTPIN (-6150 2400) $PN W34
J 2
(-6160 2410);
DISPLAY 0.489362 (-6160 2410);
PAINT MONO (-6160 2410);
FORCEPROP 0 LASTPIN (-6150 2350) $PN W35
J 2
(-6160 2360);
DISPLAY 0.489362 (-6160 2360);
PAINT MONO (-6160 2360);
FORCEPROP 0 LASTPIN (-6150 2300) $PN W36
J 2
(-6160 2310);
DISPLAY 0.489362 (-6160 2310);
PAINT MONO (-6160 2310);
FORCEPROP 0 LASTPIN (-6150 2250) $PN W40
J 2
(-6160 2260);
DISPLAY 0.489362 (-6160 2260);
PAINT MONO (-6160 2260);
FORCEPROP 0 LASTPIN (-6150 2200) $PN W41
J 2
(-6160 2210);
DISPLAY 0.489362 (-6160 2210);
PAINT MONO (-6160 2210);
FORCEPROP 0 LASTPIN (-6150 2150) $PN W42
J 2
(-6160 2160);
DISPLAY 0.489362 (-6160 2160);
PAINT MONO (-6160 2160);
FORCEPROP 0 LASTPIN (-6150 2100) $PN W45
J 2
(-6160 2110);
DISPLAY 0.489362 (-6160 2110);
PAINT MONO (-6160 2110);
FORCEPROP 0 LASTPIN (-6150 2050) $PN W48
J 2
(-6160 2060);
DISPLAY 0.489362 (-6160 2060);
PAINT MONO (-6160 2060);
FORCEPROP 0 LASTPIN (-6150 2000) $PN W51
J 2
(-6160 2010);
DISPLAY 0.489362 (-6160 2010);
PAINT MONO (-6160 2010);
FORCEPROP 0 LASTPIN (-6150 1950) $PN W54
J 2
(-6160 1960);
DISPLAY 0.489362 (-6160 1960);
PAINT MONO (-6160 1960);
FORCEPROP 0 LASTPIN (-6150 1900) $PN W56
J 2
(-6160 1910);
DISPLAY 0.489362 (-6160 1910);
PAINT MONO (-6160 1910);
FORCEPROP 0 LASTPIN (-6150 1850) $PN W58
J 2
(-6160 1860);
DISPLAY 0.489362 (-6160 1860);
PAINT MONO (-6160 1860);
FORCEPROP 0 LASTPIN (-6150 1800) $PN W61
J 2
(-6160 1810);
DISPLAY 0.489362 (-6160 1810);
PAINT MONO (-6160 1810);
FORCEPROP 0 LASTPIN (-6150 1750) $PN W63
J 2
(-6160 1760);
DISPLAY 0.489362 (-6160 1760);
PAINT MONO (-6160 1760);
FORCEPROP 0 LASTPIN (-6150 1700) $PN W65
J 2
(-6160 1710);
DISPLAY 0.489362 (-6160 1710);
PAINT MONO (-6160 1710);
FORCEPROP 0 LASTPIN (-6150 1650) $PN W68
J 2
(-6160 1660);
DISPLAY 0.489362 (-6160 1660);
PAINT MONO (-6160 1660);
FORCEPROP 0 LASTPIN (-6150 1600) $PN W70
J 2
(-6160 1610);
DISPLAY 0.489362 (-6160 1610);
PAINT MONO (-6160 1610);
FORCEPROP 0 LASTPIN (-6150 1550) $PN W72
J 2
(-6160 1560);
DISPLAY 0.489362 (-6160 1560);
PAINT MONO (-6160 1560);
FORCEPROP 0 LASTPIN (-6150 1500) $PN W75
J 2
(-6160 1510);
DISPLAY 0.489362 (-6160 1510);
PAINT MONO (-6160 1510);
FORCEPROP 0 LASTPIN (-6150 1450) $PN Y3
J 2
(-6160 1460);
DISPLAY 0.489362 (-6160 1460);
PAINT MONO (-6160 1460);
FORCEPROP 0 LASTPIN (-6150 1400) $PN Y8
J 2
(-6160 1410);
DISPLAY 0.489362 (-6160 1410);
PAINT MONO (-6160 1410);
FORCEPROP 0 LASTPIN (-6150 1350) $PN Y10
J 2
(-6160 1360);
DISPLAY 0.489362 (-6160 1360);
PAINT MONO (-6160 1360);
FORCEPROP 0 LASTPIN (-6150 1300) $PN Y15
J 2
(-6160 1310);
DISPLAY 0.489362 (-6160 1310);
PAINT MONO (-6160 1310);
FORCEPROP 0 LASTPIN (-6150 1250) $PN Y17
J 2
(-6160 1260);
DISPLAY 0.489362 (-6160 1260);
PAINT MONO (-6160 1260);
FORCEPROP 0 LASTPIN (-6150 1200) $PN Y22
J 2
(-6160 1210);
DISPLAY 0.489362 (-6160 1210);
PAINT MONO (-6160 1210);
FORCEPROP 0 LASTPIN (-6150 1150) $PN Y23
J 2
(-6160 1160);
DISPLAY 0.489362 (-6160 1160);
PAINT MONO (-6160 1160);
FORCEPROP 0 LASTPIN (-6150 1100) $PN Y24
J 2
(-6160 1110);
DISPLAY 0.489362 (-6160 1110);
PAINT MONO (-6160 1110);
FORCEPROP 0 LASTPIN (-6150 1050) $PN Y25
J 2
(-6160 1060);
DISPLAY 0.489362 (-6160 1060);
PAINT MONO (-6160 1060);
FORCEPROP 0 LASTPIN (-6150 1000) $PN Y26
J 2
(-6160 1010);
DISPLAY 0.489362 (-6160 1010);
PAINT MONO (-6160 1010);
FORCEPROP 0 LASTPIN (-6150 950) $PN Y27
J 2
(-6160 960);
DISPLAY 0.489362 (-6160 960);
PAINT MONO (-6160 960);
FORCEPROP 0 LASTPIN (-6150 900) $PN Y28
J 2
(-6160 910);
DISPLAY 0.489362 (-6160 910);
PAINT MONO (-6160 910);
FORCEPROP 0 LASTPIN (-6150 850) $PN Y31
J 2
(-6160 860);
DISPLAY 0.489362 (-6160 860);
PAINT MONO (-6160 860);
FORCEPROP 0 LASTPIN (-6150 800) $PN Y32
J 2
(-6160 810);
DISPLAY 0.489362 (-6160 810);
PAINT MONO (-6160 810);
FORCEPROP 0 LASTPIN (-6150 750) $PN Y33
J 2
(-6160 760);
DISPLAY 0.489362 (-6160 760);
PAINT MONO (-6160 760);
FORCEPROP 0 LASTPIN (-6150 700) $PN Y34
J 2
(-6160 710);
DISPLAY 0.489362 (-6160 710);
PAINT MONO (-6160 710);
FORCEPROP 0 LASTPIN (-6150 650) $PN Y37
J 2
(-6160 660);
DISPLAY 0.489362 (-6160 660);
PAINT MONO (-6160 660);
FORCEPROP 0 LASTPIN (-6150 600) $PN Y39
J 2
(-6160 610);
DISPLAY 0.489362 (-6160 610);
PAINT MONO (-6160 610);
FORCEPROP 0 LASTPIN (-6150 550) $PN Y42
J 2
(-6160 560);
DISPLAY 0.489362 (-6160 560);
PAINT MONO (-6160 560);
FORCEPROP 0 LASTPIN (-6150 500) $PN Y43
J 2
(-6160 510);
DISPLAY 0.489362 (-6160 510);
PAINT MONO (-6160 510);
FORCEPROP 0 LASTPIN (-5050 6300) $PN Y44
J 0
(-5040 6310);
DISPLAY 0.489362 (-5040 6310);
PAINT MONO (-5040 6310);
FORCEPROP 0 LASTPIN (-5050 6250) $PN Y45
J 0
(-5040 6260);
DISPLAY 0.489362 (-5040 6260);
PAINT MONO (-5040 6260);
FORCEPROP 0 LASTPIN (-5050 6200) $PN Y48
J 0
(-5040 6210);
DISPLAY 0.489362 (-5040 6210);
PAINT MONO (-5040 6210);
FORCEPROP 0 LASTPIN (-5050 6150) $PN Y49
J 0
(-5040 6160);
DISPLAY 0.489362 (-5040 6160);
PAINT MONO (-5040 6160);
FORCEPROP 0 LASTPIN (-5050 6100) $PN Y50
J 0
(-5040 6110);
DISPLAY 0.489362 (-5040 6110);
PAINT MONO (-5040 6110);
FORCEPROP 0 LASTPIN (-5050 6050) $PN Y51
J 0
(-5040 6060);
DISPLAY 0.489362 (-5040 6060);
PAINT MONO (-5040 6060);
FORCEPROP 0 LASTPIN (-5050 6000) $PN Y52
J 0
(-5040 6010);
DISPLAY 0.489362 (-5040 6010);
PAINT MONO (-5040 6010);
FORCEPROP 0 LASTPIN (-5050 5950) $PN Y53
J 0
(-5040 5960);
DISPLAY 0.489362 (-5040 5960);
PAINT MONO (-5040 5960);
FORCEPROP 0 LASTPIN (-5050 5900) $PN Y54
J 0
(-5040 5910);
DISPLAY 0.489362 (-5040 5910);
PAINT MONO (-5040 5910);
FORCEPROP 0 LASTPIN (-5050 5850) $PN Y59
J 0
(-5040 5860);
DISPLAY 0.489362 (-5040 5860);
PAINT MONO (-5040 5860);
FORCEPROP 0 LASTPIN (-5050 5800) $PN Y61
J 0
(-5040 5810);
DISPLAY 0.489362 (-5040 5810);
PAINT MONO (-5040 5810);
FORCEPROP 0 LASTPIN (-5050 5750) $PN Y66
J 0
(-5040 5760);
DISPLAY 0.489362 (-5040 5760);
PAINT MONO (-5040 5760);
FORCEPROP 0 LASTPIN (-5050 5700) $PN Y68
J 0
(-5040 5710);
DISPLAY 0.489362 (-5040 5710);
PAINT MONO (-5040 5710);
FORCEPROP 0 LASTPIN (-5050 5650) $PN Y73
J 0
(-5040 5660);
DISPLAY 0.489362 (-5040 5660);
PAINT MONO (-5040 5660);
FORCEPROP 2 LAST PART_TYPE SMLF
J 0
(-6000 6700);
DISPLAY 1.021277 (-6000 6700);
FORCEPROP 1 LAST MATERIAL IO
J 0
(-5995 6532);
DISPLAY 0.489362 (-5995 6532);
PAINT SKYBLUE (-5995 6532);
FORCEPROP 2 LAST VALUE SOCKET6096_13568-001
J 0
(-6000 6575);
DISPLAY 0.489362 (-6000 6575);
PAINT SKYBLUE (-6000 6575);
FORCEPROP 1 LAST PART_NUMBER DGA^6000030
J 0
(-5995 6650);
DISPLAY 0.489362 (-5995 6650);
PAINT SKYBLUE (-5995 6650);
FORCEPROP 1 LAST NEEDS_NO_SIZE TRUE
J 0
(-5600 3450);
DISPLAY 0.723404 (-5600 3450);
PAINT GREEN (-5600 3450);
DISPLAY INVISIBLE (-5600 3450);
FORCEPROP 1 LAST CDS_LMAN_SYM_OUTLINE -400,3050,400,-3050
J 0
(-5600 3450);
DISPLAY 0.468085 (-5600 3450);
PAINT GREEN (-5600 3450);
DISPLAY INVISIBLE (-5600 3450);
FORCEPROP 2 LAST CDS_LIB pure_quanta
J 0
(-5600 3450);
DISPLAY INVISIBLE (-5600 3450);
FORCEPROP 1 LAST PATH I21
J 0
(-5600 3450);
DISPLAY 0.723404 (-5600 3450);
PAINT GREEN (-5600 3450);
DISPLAY INVISIBLE (-5600 3450);
FORCEADD GENOA_SP5..31
(-4100 3475);
FORCEPROP 1 LAST LOCATION U25
J 0
(-4495 6600);
DISPLAY 0.489362 (-4495 6600);
PAINT SKYBLUE (-4495 6600);
FORCEPROP 0 LAST $SEC 31
J 0
(-4475 6875);
DISPLAY 0.680851 (-4475 6875);
PAINT MONO (-4475 6875);
DISPLAY INVISIBLE (-4475 6875);
FORCEPROP 0 LAST CDS_SEC 31
J 0
(-4700 6725);
DISPLAY 1.021277 (-4700 6725);
DISPLAY INVISIBLE (-4700 6725);
FORCEPROP 0 LASTPIN (-4650 6375) $PN AD49
J 2
(-4635 6385);
DISPLAY 0.489362 (-4635 6385);
PAINT MONO (-4635 6385);
FORCEPROP 0 LASTPIN (-4650 6325) $PN AD50
J 2
(-4635 6335);
DISPLAY 0.489362 (-4635 6335);
PAINT MONO (-4635 6335);
FORCEPROP 0 LASTPIN (-4650 6275) $PN AD51
J 2
(-4635 6285);
DISPLAY 0.489362 (-4635 6285);
PAINT MONO (-4635 6285);
FORCEPROP 0 LASTPIN (-4650 6225) $PN AD52
J 2
(-4635 6235);
DISPLAY 0.489362 (-4635 6235);
PAINT MONO (-4635 6235);
FORCEPROP 0 LASTPIN (-4650 6175) $PN AD53
J 2
(-4635 6185);
DISPLAY 0.489362 (-4635 6185);
PAINT MONO (-4635 6185);
FORCEPROP 0 LASTPIN (-4650 6125) $PN AD57
J 2
(-4635 6135);
DISPLAY 0.489362 (-4635 6135);
PAINT MONO (-4635 6135);
FORCEPROP 0 LASTPIN (-4650 6075) $PN AD59
J 2
(-4635 6085);
DISPLAY 0.489362 (-4635 6085);
PAINT MONO (-4635 6085);
FORCEPROP 0 LASTPIN (-4650 6025) $PN AD61
J 2
(-4635 6035);
DISPLAY 0.489362 (-4635 6035);
PAINT MONO (-4635 6035);
FORCEPROP 0 LASTPIN (-4650 5975) $PN AD64
J 2
(-4635 5985);
DISPLAY 0.489362 (-4635 5985);
PAINT MONO (-4635 5985);
FORCEPROP 0 LASTPIN (-4650 5925) $PN AD66
J 2
(-4635 5935);
DISPLAY 0.489362 (-4635 5935);
PAINT MONO (-4635 5935);
FORCEPROP 0 LASTPIN (-4650 5875) $PN AD68
J 2
(-4635 5885);
DISPLAY 0.489362 (-4635 5885);
PAINT MONO (-4635 5885);
FORCEPROP 0 LASTPIN (-4650 5825) $PN AD71
J 2
(-4635 5835);
DISPLAY 0.489362 (-4635 5835);
PAINT MONO (-4635 5835);
FORCEPROP 0 LASTPIN (-4650 5775) $PN AD73
J 2
(-4635 5785);
DISPLAY 0.489362 (-4635 5785);
PAINT MONO (-4635 5785);
FORCEPROP 0 LASTPIN (-4650 5725) $PN AE1
J 2
(-4635 5735);
DISPLAY 0.489362 (-4635 5735);
PAINT MONO (-4635 5735);
FORCEPROP 0 LASTPIN (-4650 5675) $PN AE6
J 2
(-4635 5685);
DISPLAY 0.489362 (-4635 5685);
PAINT MONO (-4635 5685);
FORCEPROP 0 LASTPIN (-4650 5625) $PN AE8
J 2
(-4635 5635);
DISPLAY 0.489362 (-4635 5635);
PAINT MONO (-4635 5635);
FORCEPROP 0 LASTPIN (-4650 5575) $PN AE11
J 2
(-4635 5585);
DISPLAY 0.489362 (-4635 5585);
PAINT MONO (-4635 5585);
FORCEPROP 0 LASTPIN (-4650 5525) $PN AE13
J 2
(-4635 5535);
DISPLAY 0.489362 (-4635 5535);
PAINT MONO (-4635 5535);
FORCEPROP 0 LASTPIN (-4650 5475) $PN AE15
J 2
(-4635 5485);
DISPLAY 0.489362 (-4635 5485);
PAINT MONO (-4635 5485);
FORCEPROP 0 LASTPIN (-4650 5425) $PN AE18
J 2
(-4635 5435);
DISPLAY 0.489362 (-4635 5435);
PAINT MONO (-4635 5435);
FORCEPROP 0 LASTPIN (-4650 5375) $PN AE20
J 2
(-4635 5385);
DISPLAY 0.489362 (-4635 5385);
PAINT MONO (-4635 5385);
FORCEPROP 0 LASTPIN (-4650 5325) $PN AE22
J 2
(-4635 5335);
DISPLAY 0.489362 (-4635 5335);
PAINT MONO (-4635 5335);
FORCEPROP 0 LASTPIN (-4650 5275) $PN AE25
J 2
(-4635 5285);
DISPLAY 0.489362 (-4635 5285);
PAINT MONO (-4635 5285);
FORCEPROP 0 LASTPIN (-4650 5225) $PN AE28
J 2
(-4635 5235);
DISPLAY 0.489362 (-4635 5235);
PAINT MONO (-4635 5235);
FORCEPROP 0 LASTPIN (-4650 5175) $PN AE31
J 2
(-4635 5185);
DISPLAY 0.489362 (-4635 5185);
PAINT MONO (-4635 5185);
FORCEPROP 0 LASTPIN (-4650 5125) $PN AE34
J 2
(-4635 5135);
DISPLAY 0.489362 (-4635 5135);
PAINT MONO (-4635 5135);
FORCEPROP 0 LASTPIN (-4650 5075) $PN AE35
J 2
(-4635 5085);
DISPLAY 0.489362 (-4635 5085);
PAINT MONO (-4635 5085);
FORCEPROP 0 LASTPIN (-4650 5025) $PN AE36
J 2
(-4635 5035);
DISPLAY 0.489362 (-4635 5035);
PAINT MONO (-4635 5035);
FORCEPROP 0 LASTPIN (-4650 4975) $PN AE40
J 2
(-4635 4985);
DISPLAY 0.489362 (-4635 4985);
PAINT MONO (-4635 4985);
FORCEPROP 0 LASTPIN (-4650 4925) $PN AE41
J 2
(-4635 4935);
DISPLAY 0.489362 (-4635 4935);
PAINT MONO (-4635 4935);
FORCEPROP 0 LASTPIN (-4650 4875) $PN AE42
J 2
(-4635 4885);
DISPLAY 0.489362 (-4635 4885);
PAINT MONO (-4635 4885);
FORCEPROP 0 LASTPIN (-4650 4825) $PN AE45
J 2
(-4635 4835);
DISPLAY 0.489362 (-4635 4835);
PAINT MONO (-4635 4835);
FORCEPROP 0 LASTPIN (-4650 4775) $PN AE48
J 2
(-4635 4785);
DISPLAY 0.489362 (-4635 4785);
PAINT MONO (-4635 4785);
FORCEPROP 0 LASTPIN (-4650 4725) $PN AE51
J 2
(-4635 4735);
DISPLAY 0.489362 (-4635 4735);
PAINT MONO (-4635 4735);
FORCEPROP 0 LASTPIN (-4650 4675) $PN AE54
J 2
(-4635 4685);
DISPLAY 0.489362 (-4635 4685);
PAINT MONO (-4635 4685);
FORCEPROP 0 LASTPIN (-4650 4625) $PN AE56
J 2
(-4635 4635);
DISPLAY 0.489362 (-4635 4635);
PAINT MONO (-4635 4635);
FORCEPROP 0 LASTPIN (-4650 4575) $PN AE58
J 2
(-4635 4585);
DISPLAY 0.489362 (-4635 4585);
PAINT MONO (-4635 4585);
FORCEPROP 0 LASTPIN (-4650 4525) $PN AE61
J 2
(-4635 4535);
DISPLAY 0.489362 (-4635 4535);
PAINT MONO (-4635 4535);
FORCEPROP 0 LASTPIN (-4650 4475) $PN AE63
J 2
(-4635 4485);
DISPLAY 0.489362 (-4635 4485);
PAINT MONO (-4635 4485);
FORCEPROP 0 LASTPIN (-4650 4425) $PN AE65
J 2
(-4635 4435);
DISPLAY 0.489362 (-4635 4435);
PAINT MONO (-4635 4435);
FORCEPROP 0 LASTPIN (-4650 4375) $PN AE68
J 2
(-4635 4385);
DISPLAY 0.489362 (-4635 4385);
PAINT MONO (-4635 4385);
FORCEPROP 0 LASTPIN (-4650 4325) $PN AE70
J 2
(-4635 4335);
DISPLAY 0.489362 (-4635 4335);
PAINT MONO (-4635 4335);
FORCEPROP 0 LASTPIN (-4650 4275) $PN AE72
J 2
(-4635 4285);
DISPLAY 0.489362 (-4635 4285);
PAINT MONO (-4635 4285);
FORCEPROP 0 LASTPIN (-4650 4225) $PN AE75
J 2
(-4635 4235);
DISPLAY 0.489362 (-4635 4235);
PAINT MONO (-4635 4235);
FORCEPROP 0 LASTPIN (-4650 4175) $PN AF3
J 2
(-4635 4185);
DISPLAY 0.489362 (-4635 4185);
PAINT MONO (-4635 4185);
FORCEPROP 0 LASTPIN (-4650 4125) $PN AF8
J 2
(-4635 4135);
DISPLAY 0.489362 (-4635 4135);
PAINT MONO (-4635 4135);
FORCEPROP 0 LASTPIN (-4650 4075) $PN AF10
J 2
(-4635 4085);
DISPLAY 0.489362 (-4635 4085);
PAINT MONO (-4635 4085);
FORCEPROP 0 LASTPIN (-4650 4025) $PN AF15
J 2
(-4635 4035);
DISPLAY 0.489362 (-4635 4035);
PAINT MONO (-4635 4035);
FORCEPROP 0 LASTPIN (-4650 3975) $PN AF17
J 2
(-4635 3985);
DISPLAY 0.489362 (-4635 3985);
PAINT MONO (-4635 3985);
FORCEPROP 0 LASTPIN (-4650 3925) $PN AF22
J 2
(-4635 3935);
DISPLAY 0.489362 (-4635 3935);
PAINT MONO (-4635 3935);
FORCEPROP 0 LASTPIN (-4650 3875) $PN AF25
J 2
(-4635 3885);
DISPLAY 0.489362 (-4635 3885);
PAINT MONO (-4635 3885);
FORCEPROP 0 LASTPIN (-4650 3825) $PN AF28
J 2
(-4635 3835);
DISPLAY 0.489362 (-4635 3835);
PAINT MONO (-4635 3835);
FORCEPROP 0 LASTPIN (-4650 3775) $PN AF31
J 2
(-4635 3785);
DISPLAY 0.489362 (-4635 3785);
PAINT MONO (-4635 3785);
FORCEPROP 0 LASTPIN (-4650 3725) $PN AF34
J 2
(-4635 3735);
DISPLAY 0.489362 (-4635 3735);
PAINT MONO (-4635 3735);
FORCEPROP 0 LASTPIN (-4650 3675) $PN AF37
J 2
(-4635 3685);
DISPLAY 0.489362 (-4635 3685);
PAINT MONO (-4635 3685);
FORCEPROP 0 LASTPIN (-4650 3625) $PN AF39
J 2
(-4635 3635);
DISPLAY 0.489362 (-4635 3635);
PAINT MONO (-4635 3635);
FORCEPROP 0 LASTPIN (-4650 3575) $PN AF42
J 2
(-4635 3585);
DISPLAY 0.489362 (-4635 3585);
PAINT MONO (-4635 3585);
FORCEPROP 0 LASTPIN (-4650 3525) $PN AF45
J 2
(-4635 3535);
DISPLAY 0.489362 (-4635 3535);
PAINT MONO (-4635 3535);
FORCEPROP 0 LASTPIN (-4650 3475) $PN AF48
J 2
(-4635 3485);
DISPLAY 0.489362 (-4635 3485);
PAINT MONO (-4635 3485);
FORCEPROP 0 LASTPIN (-4650 3425) $PN AF51
J 2
(-4635 3435);
DISPLAY 0.489362 (-4635 3435);
PAINT MONO (-4635 3435);
FORCEPROP 0 LASTPIN (-4650 3375) $PN AF54
J 2
(-4635 3385);
DISPLAY 0.489362 (-4635 3385);
PAINT MONO (-4635 3385);
FORCEPROP 0 LASTPIN (-4650 3325) $PN AF59
J 2
(-4635 3335);
DISPLAY 0.489362 (-4635 3335);
PAINT MONO (-4635 3335);
FORCEPROP 0 LASTPIN (-4650 3275) $PN AF61
J 2
(-4635 3285);
DISPLAY 0.489362 (-4635 3285);
PAINT MONO (-4635 3285);
FORCEPROP 0 LASTPIN (-4650 3225) $PN AF66
J 2
(-4635 3235);
DISPLAY 0.489362 (-4635 3235);
PAINT MONO (-4635 3235);
FORCEPROP 0 LASTPIN (-4650 3175) $PN AF68
J 2
(-4635 3185);
DISPLAY 0.489362 (-4635 3185);
PAINT MONO (-4635 3185);
FORCEPROP 0 LASTPIN (-4650 3125) $PN AF73
J 2
(-4635 3135);
DISPLAY 0.489362 (-4635 3135);
PAINT MONO (-4635 3135);
FORCEPROP 0 LASTPIN (-4650 3075) $PN AG1
J 2
(-4635 3085);
DISPLAY 0.489362 (-4635 3085);
PAINT MONO (-4635 3085);
FORCEPROP 0 LASTPIN (-4650 3025) $PN AG4
J 2
(-4635 3035);
DISPLAY 0.489362 (-4635 3035);
PAINT MONO (-4635 3035);
FORCEPROP 0 LASTPIN (-4650 2975) $PN AG6
J 2
(-4635 2985);
DISPLAY 0.489362 (-4635 2985);
PAINT MONO (-4635 2985);
FORCEPROP 0 LASTPIN (-4650 2925) $PN AG8
J 2
(-4635 2935);
DISPLAY 0.489362 (-4635 2935);
PAINT MONO (-4635 2935);
FORCEPROP 0 LASTPIN (-4650 2875) $PN AG11
J 2
(-4635 2885);
DISPLAY 0.489362 (-4635 2885);
PAINT MONO (-4635 2885);
FORCEPROP 0 LASTPIN (-4650 2825) $PN AG13
J 2
(-4635 2835);
DISPLAY 0.489362 (-4635 2835);
PAINT MONO (-4635 2835);
FORCEPROP 0 LASTPIN (-4650 2775) $PN AG15
J 2
(-4635 2785);
DISPLAY 0.489362 (-4635 2785);
PAINT MONO (-4635 2785);
FORCEPROP 0 LASTPIN (-4650 2725) $PN AG18
J 2
(-4635 2735);
DISPLAY 0.489362 (-4635 2735);
PAINT MONO (-4635 2735);
FORCEPROP 0 LASTPIN (-4650 2675) $PN AG20
J 2
(-4635 2685);
DISPLAY 0.489362 (-4635 2685);
PAINT MONO (-4635 2685);
FORCEPROP 0 LASTPIN (-4650 2625) $PN AG22
J 2
(-4635 2635);
DISPLAY 0.489362 (-4635 2635);
PAINT MONO (-4635 2635);
FORCEPROP 0 LASTPIN (-4650 2575) $PN AG25
J 2
(-4635 2585);
DISPLAY 0.489362 (-4635 2585);
PAINT MONO (-4635 2585);
FORCEPROP 0 LASTPIN (-4650 2525) $PN AG28
J 2
(-4635 2535);
DISPLAY 0.489362 (-4635 2535);
PAINT MONO (-4635 2535);
FORCEPROP 0 LASTPIN (-4650 2475) $PN AG31
J 2
(-4635 2485);
DISPLAY 0.489362 (-4635 2485);
PAINT MONO (-4635 2485);
FORCEPROP 0 LASTPIN (-4650 2425) $PN AG34
J 2
(-4635 2435);
DISPLAY 0.489362 (-4635 2435);
PAINT MONO (-4635 2435);
FORCEPROP 0 LASTPIN (-4650 2375) $PN AG42
J 2
(-4635 2385);
DISPLAY 0.489362 (-4635 2385);
PAINT MONO (-4635 2385);
FORCEPROP 0 LASTPIN (-4650 2325) $PN AG45
J 2
(-4635 2335);
DISPLAY 0.489362 (-4635 2335);
PAINT MONO (-4635 2335);
FORCEPROP 0 LASTPIN (-4650 2275) $PN AG48
J 2
(-4635 2285);
DISPLAY 0.489362 (-4635 2285);
PAINT MONO (-4635 2285);
FORCEPROP 0 LASTPIN (-4650 2225) $PN AG51
J 2
(-4635 2235);
DISPLAY 0.489362 (-4635 2235);
PAINT MONO (-4635 2235);
FORCEPROP 0 LASTPIN (-4650 2175) $PN AG54
J 2
(-4635 2185);
DISPLAY 0.489362 (-4635 2185);
PAINT MONO (-4635 2185);
FORCEPROP 0 LASTPIN (-4650 2125) $PN AG56
J 2
(-4635 2135);
DISPLAY 0.489362 (-4635 2135);
PAINT MONO (-4635 2135);
FORCEPROP 0 LASTPIN (-4650 2075) $PN AG58
J 2
(-4635 2085);
DISPLAY 0.489362 (-4635 2085);
PAINT MONO (-4635 2085);
FORCEPROP 0 LASTPIN (-4650 2025) $PN AG61
J 2
(-4635 2035);
DISPLAY 0.489362 (-4635 2035);
PAINT MONO (-4635 2035);
FORCEPROP 0 LASTPIN (-4650 1975) $PN AG63
J 2
(-4635 1985);
DISPLAY 0.489362 (-4635 1985);
PAINT MONO (-4635 1985);
FORCEPROP 0 LASTPIN (-4650 1925) $PN AG65
J 2
(-4635 1935);
DISPLAY 0.489362 (-4635 1935);
PAINT MONO (-4635 1935);
FORCEPROP 0 LASTPIN (-4650 1875) $PN AG68
J 2
(-4635 1885);
DISPLAY 0.489362 (-4635 1885);
PAINT MONO (-4635 1885);
FORCEPROP 0 LASTPIN (-4650 1825) $PN AG70
J 2
(-4635 1835);
DISPLAY 0.489362 (-4635 1835);
PAINT MONO (-4635 1835);
FORCEPROP 0 LASTPIN (-4650 1775) $PN AG72
J 2
(-4635 1785);
DISPLAY 0.489362 (-4635 1785);
PAINT MONO (-4635 1785);
FORCEPROP 0 LASTPIN (-4650 1725) $PN AG75
J 2
(-4635 1735);
DISPLAY 0.489362 (-4635 1735);
PAINT MONO (-4635 1735);
FORCEPROP 0 LASTPIN (-4650 1675) $PN AH3
J 2
(-4635 1685);
DISPLAY 0.489362 (-4635 1685);
PAINT MONO (-4635 1685);
FORCEPROP 0 LASTPIN (-4650 1625) $PN AH5
J 2
(-4635 1635);
DISPLAY 0.489362 (-4635 1635);
PAINT MONO (-4635 1635);
FORCEPROP 0 LASTPIN (-4650 1575) $PN AH8
J 2
(-4635 1585);
DISPLAY 0.489362 (-4635 1585);
PAINT MONO (-4635 1585);
FORCEPROP 0 LASTPIN (-4650 1525) $PN AH10
J 2
(-4635 1535);
DISPLAY 0.489362 (-4635 1535);
PAINT MONO (-4635 1535);
FORCEPROP 0 LASTPIN (-4650 1475) $PN AH12
J 2
(-4635 1485);
DISPLAY 0.489362 (-4635 1485);
PAINT MONO (-4635 1485);
FORCEPROP 0 LASTPIN (-4650 1425) $PN AH15
J 2
(-4635 1435);
DISPLAY 0.489362 (-4635 1435);
PAINT MONO (-4635 1435);
FORCEPROP 0 LASTPIN (-4650 1375) $PN AH17
J 2
(-4635 1385);
DISPLAY 0.489362 (-4635 1385);
PAINT MONO (-4635 1385);
FORCEPROP 0 LASTPIN (-4650 1325) $PN AH19
J 2
(-4635 1335);
DISPLAY 0.489362 (-4635 1335);
PAINT MONO (-4635 1335);
FORCEPROP 0 LASTPIN (-4650 1275) $PN AH23
J 2
(-4635 1285);
DISPLAY 0.489362 (-4635 1285);
PAINT MONO (-4635 1285);
FORCEPROP 0 LASTPIN (-4650 1225) $PN AH24
J 2
(-4635 1235);
DISPLAY 0.489362 (-4635 1235);
PAINT MONO (-4635 1235);
FORCEPROP 0 LASTPIN (-4650 1175) $PN AH25
J 2
(-4635 1185);
DISPLAY 0.489362 (-4635 1185);
PAINT MONO (-4635 1185);
FORCEPROP 0 LASTPIN (-4650 1125) $PN AH26
J 2
(-4635 1135);
DISPLAY 0.489362 (-4635 1135);
PAINT MONO (-4635 1135);
FORCEPROP 0 LASTPIN (-4650 1075) $PN AH27
J 2
(-4635 1085);
DISPLAY 0.489362 (-4635 1085);
PAINT MONO (-4635 1085);
FORCEPROP 0 LASTPIN (-4650 1025) $PN AH28
J 2
(-4635 1035);
DISPLAY 0.489362 (-4635 1035);
PAINT MONO (-4635 1035);
FORCEPROP 0 LASTPIN (-4650 975) $PN AH29
J 2
(-4635 985);
DISPLAY 0.489362 (-4635 985);
PAINT MONO (-4635 985);
FORCEPROP 0 LASTPIN (-4650 925) $PN AH30
J 2
(-4635 935);
DISPLAY 0.489362 (-4635 935);
PAINT MONO (-4635 935);
FORCEPROP 0 LASTPIN (-4650 875) $PN AH31
J 2
(-4635 885);
DISPLAY 0.489362 (-4635 885);
PAINT MONO (-4635 885);
FORCEPROP 0 LASTPIN (-4650 825) $PN AH32
J 2
(-4635 835);
DISPLAY 0.489362 (-4635 835);
PAINT MONO (-4635 835);
FORCEPROP 0 LASTPIN (-4650 775) $PN AH34
J 2
(-4635 785);
DISPLAY 0.489362 (-4635 785);
PAINT MONO (-4635 785);
FORCEPROP 0 LASTPIN (-4650 725) $PN AH37
J 2
(-4635 735);
DISPLAY 0.489362 (-4635 735);
PAINT MONO (-4635 735);
FORCEPROP 0 LASTPIN (-4650 675) $PN AH39
J 2
(-4635 685);
DISPLAY 0.489362 (-4635 685);
PAINT MONO (-4635 685);
FORCEPROP 0 LASTPIN (-4650 625) $PN AH42
J 2
(-4635 635);
DISPLAY 0.489362 (-4635 635);
PAINT MONO (-4635 635);
FORCEPROP 0 LASTPIN (-4650 575) $PN AH43
J 2
(-4635 585);
DISPLAY 0.489362 (-4635 585);
PAINT MONO (-4635 585);
FORCEPROP 0 LASTPIN (-3550 6375) $PN AH44
J 0
(-3540 6385);
DISPLAY 0.489362 (-3540 6385);
PAINT MONO (-3540 6385);
FORCEPROP 0 LASTPIN (-3550 6325) $PN AH45
J 0
(-3540 6335);
DISPLAY 0.489362 (-3540 6335);
PAINT MONO (-3540 6335);
FORCEPROP 0 LASTPIN (-3550 6275) $PN AH46
J 0
(-3540 6285);
DISPLAY 0.489362 (-3540 6285);
PAINT MONO (-3540 6285);
FORCEPROP 0 LASTPIN (-3550 6225) $PN AH47
J 0
(-3540 6235);
DISPLAY 0.489362 (-3540 6235);
PAINT MONO (-3540 6235);
FORCEPROP 0 LASTPIN (-3550 6175) $PN AH48
J 0
(-3540 6185);
DISPLAY 0.489362 (-3540 6185);
PAINT MONO (-3540 6185);
FORCEPROP 0 LASTPIN (-3550 6125) $PN AH49
J 0
(-3540 6135);
DISPLAY 0.489362 (-3540 6135);
PAINT MONO (-3540 6135);
FORCEPROP 0 LASTPIN (-3550 6075) $PN AH50
J 0
(-3540 6085);
DISPLAY 0.489362 (-3540 6085);
PAINT MONO (-3540 6085);
FORCEPROP 0 LASTPIN (-3550 6025) $PN AH51
J 0
(-3540 6035);
DISPLAY 0.489362 (-3540 6035);
PAINT MONO (-3540 6035);
FORCEPROP 0 LASTPIN (-3550 5975) $PN AH52
J 0
(-3540 5985);
DISPLAY 0.489362 (-3540 5985);
PAINT MONO (-3540 5985);
FORCEPROP 0 LASTPIN (-3550 5925) $PN AH53
J 0
(-3540 5935);
DISPLAY 0.489362 (-3540 5935);
PAINT MONO (-3540 5935);
FORCEPROP 0 LASTPIN (-3550 5875) $PN AH57
J 0
(-3540 5885);
DISPLAY 0.489362 (-3540 5885);
PAINT MONO (-3540 5885);
FORCEPROP 0 LASTPIN (-3550 5825) $PN AH59
J 0
(-3540 5835);
DISPLAY 0.489362 (-3540 5835);
PAINT MONO (-3540 5835);
FORCEPROP 0 LASTPIN (-3550 5775) $PN AH61
J 0
(-3540 5785);
DISPLAY 0.489362 (-3540 5785);
PAINT MONO (-3540 5785);
FORCEPROP 0 LASTPIN (-3550 5725) $PN AH64
J 0
(-3540 5735);
DISPLAY 0.489362 (-3540 5735);
PAINT MONO (-3540 5735);
FORCEPROP 0 LASTPIN (-3550 5675) $PN AH66
J 0
(-3540 5685);
DISPLAY 0.489362 (-3540 5685);
PAINT MONO (-3540 5685);
FORCEPROP 0 LASTPIN (-3550 5625) $PN AH68
J 0
(-3540 5635);
DISPLAY 0.489362 (-3540 5635);
PAINT MONO (-3540 5635);
FORCEPROP 0 LASTPIN (-3550 5575) $PN AH71
J 0
(-3540 5585);
DISPLAY 0.489362 (-3540 5585);
PAINT MONO (-3540 5585);
FORCEPROP 0 LASTPIN (-3550 5525) $PN AH73
J 0
(-3540 5535);
DISPLAY 0.489362 (-3540 5535);
PAINT MONO (-3540 5535);
FORCEPROP 0 LASTPIN (-3550 5475) $PN AJ1
J 0
(-3540 5485);
DISPLAY 0.489362 (-3540 5485);
PAINT MONO (-3540 5485);
FORCEPROP 0 LASTPIN (-3550 5425) $PN AJ6
J 0
(-3540 5435);
DISPLAY 0.489362 (-3540 5435);
PAINT MONO (-3540 5435);
FORCEPROP 0 LASTPIN (-3550 5375) $PN AJ8
J 0
(-3540 5385);
DISPLAY 0.489362 (-3540 5385);
PAINT MONO (-3540 5385);
FORCEPROP 0 LASTPIN (-3550 5325) $PN AJ15
J 0
(-3540 5335);
DISPLAY 0.489362 (-3540 5335);
PAINT MONO (-3540 5335);
FORCEPROP 0 LASTPIN (-3550 5275) $PN AJ20
J 0
(-3540 5285);
DISPLAY 0.489362 (-3540 5285);
PAINT MONO (-3540 5285);
FORCEPROP 0 LASTPIN (-3550 5225) $PN AJ22
J 0
(-3540 5235);
DISPLAY 0.489362 (-3540 5235);
PAINT MONO (-3540 5235);
FORCEPROP 0 LASTPIN (-3550 5175) $PN AJ25
J 0
(-3540 5185);
DISPLAY 0.489362 (-3540 5185);
PAINT MONO (-3540 5185);
FORCEPROP 0 LASTPIN (-3550 5125) $PN AJ28
J 0
(-3540 5135);
DISPLAY 0.489362 (-3540 5135);
PAINT MONO (-3540 5135);
FORCEPROP 0 LASTPIN (-3550 5075) $PN AJ31
J 0
(-3540 5085);
DISPLAY 0.489362 (-3540 5085);
PAINT MONO (-3540 5085);
FORCEPROP 0 LASTPIN (-3550 5025) $PN AJ34
J 0
(-3540 5035);
DISPLAY 0.489362 (-3540 5035);
PAINT MONO (-3540 5035);
FORCEPROP 0 LASTPIN (-3550 4975) $PN AJ35
J 0
(-3540 4985);
DISPLAY 0.489362 (-3540 4985);
PAINT MONO (-3540 4985);
FORCEPROP 0 LASTPIN (-3550 4925) $PN AJ36
J 0
(-3540 4935);
DISPLAY 0.489362 (-3540 4935);
PAINT MONO (-3540 4935);
FORCEPROP 0 LASTPIN (-3550 4875) $PN AJ40
J 0
(-3540 4885);
DISPLAY 0.489362 (-3540 4885);
PAINT MONO (-3540 4885);
FORCEPROP 0 LASTPIN (-3550 4825) $PN AJ41
J 0
(-3540 4835);
DISPLAY 0.489362 (-3540 4835);
PAINT MONO (-3540 4835);
FORCEPROP 0 LASTPIN (-3550 4775) $PN AJ42
J 0
(-3540 4785);
DISPLAY 0.489362 (-3540 4785);
PAINT MONO (-3540 4785);
FORCEPROP 0 LASTPIN (-3550 4725) $PN AJ45
J 0
(-3540 4735);
DISPLAY 0.489362 (-3540 4735);
PAINT MONO (-3540 4735);
FORCEPROP 0 LASTPIN (-3550 4675) $PN AJ48
J 0
(-3540 4685);
DISPLAY 0.489362 (-3540 4685);
PAINT MONO (-3540 4685);
FORCEPROP 0 LASTPIN (-3550 4625) $PN AJ51
J 0
(-3540 4635);
DISPLAY 0.489362 (-3540 4635);
PAINT MONO (-3540 4635);
FORCEPROP 0 LASTPIN (-3550 4575) $PN AJ54
J 0
(-3540 4585);
DISPLAY 0.489362 (-3540 4585);
PAINT MONO (-3540 4585);
FORCEPROP 0 LASTPIN (-3550 4525) $PN AJ56
J 0
(-3540 4535);
DISPLAY 0.489362 (-3540 4535);
PAINT MONO (-3540 4535);
FORCEPROP 0 LASTPIN (-3550 4475) $PN AJ61
J 0
(-3540 4485);
DISPLAY 0.489362 (-3540 4485);
PAINT MONO (-3540 4485);
FORCEPROP 0 LASTPIN (-3550 4425) $PN AJ63
J 0
(-3540 4435);
DISPLAY 0.489362 (-3540 4435);
PAINT MONO (-3540 4435);
FORCEPROP 0 LASTPIN (-3550 4375) $PN AJ68
J 0
(-3540 4385);
DISPLAY 0.489362 (-3540 4385);
PAINT MONO (-3540 4385);
FORCEPROP 0 LASTPIN (-3550 4325) $PN AJ70
J 0
(-3540 4335);
DISPLAY 0.489362 (-3540 4335);
PAINT MONO (-3540 4335);
FORCEPROP 0 LASTPIN (-3550 4275) $PN AJ75
J 0
(-3540 4285);
DISPLAY 0.489362 (-3540 4285);
PAINT MONO (-3540 4285);
FORCEPROP 0 LASTPIN (-3550 4225) $PN AK3
J 0
(-3540 4235);
DISPLAY 0.489362 (-3540 4235);
PAINT MONO (-3540 4235);
FORCEPROP 0 LASTPIN (-3550 4175) $PN AK5
J 0
(-3540 4185);
DISPLAY 0.489362 (-3540 4185);
PAINT MONO (-3540 4185);
FORCEPROP 0 LASTPIN (-3550 4125) $PN AK8
J 0
(-3540 4135);
DISPLAY 0.489362 (-3540 4135);
PAINT MONO (-3540 4135);
FORCEPROP 0 LASTPIN (-3550 4075) $PN AK10
J 0
(-3540 4085);
DISPLAY 0.489362 (-3540 4085);
PAINT MONO (-3540 4085);
FORCEPROP 0 LASTPIN (-3550 4025) $PN AK12
J 0
(-3540 4035);
DISPLAY 0.489362 (-3540 4035);
PAINT MONO (-3540 4035);
FORCEPROP 0 LASTPIN (-3550 3975) $PN AK15
J 0
(-3540 3985);
DISPLAY 0.489362 (-3540 3985);
PAINT MONO (-3540 3985);
FORCEPROP 0 LASTPIN (-3550 3925) $PN AK17
J 0
(-3540 3935);
DISPLAY 0.489362 (-3540 3935);
PAINT MONO (-3540 3935);
FORCEPROP 0 LASTPIN (-3550 3875) $PN AK19
J 0
(-3540 3885);
DISPLAY 0.489362 (-3540 3885);
PAINT MONO (-3540 3885);
FORCEPROP 0 LASTPIN (-3550 3825) $PN AK22
J 0
(-3540 3835);
DISPLAY 0.489362 (-3540 3835);
PAINT MONO (-3540 3835);
FORCEPROP 0 LASTPIN (-3550 3775) $PN AK25
J 0
(-3540 3785);
DISPLAY 0.489362 (-3540 3785);
PAINT MONO (-3540 3785);
FORCEPROP 0 LASTPIN (-3550 3725) $PN AK28
J 0
(-3540 3735);
DISPLAY 0.489362 (-3540 3735);
PAINT MONO (-3540 3735);
FORCEPROP 0 LASTPIN (-3550 3675) $PN AK31
J 0
(-3540 3685);
DISPLAY 0.489362 (-3540 3685);
PAINT MONO (-3540 3685);
FORCEPROP 0 LASTPIN (-3550 3625) $PN AK34
J 0
(-3540 3635);
DISPLAY 0.489362 (-3540 3635);
PAINT MONO (-3540 3635);
FORCEPROP 0 LASTPIN (-3550 3575) $PN AK37
J 0
(-3540 3585);
DISPLAY 0.489362 (-3540 3585);
PAINT MONO (-3540 3585);
FORCEPROP 0 LASTPIN (-3550 3525) $PN AK39
J 0
(-3540 3535);
DISPLAY 0.489362 (-3540 3535);
PAINT MONO (-3540 3535);
FORCEPROP 0 LASTPIN (-3550 3475) $PN AK42
J 0
(-3540 3485);
DISPLAY 0.489362 (-3540 3485);
PAINT MONO (-3540 3485);
FORCEPROP 0 LASTPIN (-3550 3425) $PN AK45
J 0
(-3540 3435);
DISPLAY 0.489362 (-3540 3435);
PAINT MONO (-3540 3435);
FORCEPROP 0 LASTPIN (-3550 3375) $PN AK48
J 0
(-3540 3385);
DISPLAY 0.489362 (-3540 3385);
PAINT MONO (-3540 3385);
FORCEPROP 0 LASTPIN (-3550 3325) $PN AK51
J 0
(-3540 3335);
DISPLAY 0.489362 (-3540 3335);
PAINT MONO (-3540 3335);
FORCEPROP 0 LASTPIN (-3550 3275) $PN AK54
J 0
(-3540 3285);
DISPLAY 0.489362 (-3540 3285);
PAINT MONO (-3540 3285);
FORCEPROP 0 LASTPIN (-3550 3225) $PN AK57
J 0
(-3540 3235);
DISPLAY 0.489362 (-3540 3235);
PAINT MONO (-3540 3235);
FORCEPROP 0 LASTPIN (-3550 3175) $PN AK59
J 0
(-3540 3185);
DISPLAY 0.489362 (-3540 3185);
PAINT MONO (-3540 3185);
FORCEPROP 0 LASTPIN (-3550 3125) $PN AK61
J 0
(-3540 3135);
DISPLAY 0.489362 (-3540 3135);
PAINT MONO (-3540 3135);
FORCEPROP 0 LASTPIN (-3550 3075) $PN AK64
J 0
(-3540 3085);
DISPLAY 0.489362 (-3540 3085);
PAINT MONO (-3540 3085);
FORCEPROP 0 LASTPIN (-3550 3025) $PN AK66
J 0
(-3540 3035);
DISPLAY 0.489362 (-3540 3035);
PAINT MONO (-3540 3035);
FORCEPROP 0 LASTPIN (-3550 2975) $PN AK68
J 0
(-3540 2985);
DISPLAY 0.489362 (-3540 2985);
PAINT MONO (-3540 2985);
FORCEPROP 0 LASTPIN (-3550 2925) $PN AK71
J 0
(-3540 2935);
DISPLAY 0.489362 (-3540 2935);
PAINT MONO (-3540 2935);
FORCEPROP 0 LASTPIN (-3550 2875) $PN AK73
J 0
(-3540 2885);
DISPLAY 0.489362 (-3540 2885);
PAINT MONO (-3540 2885);
FORCEPROP 0 LASTPIN (-3550 2825) $PN AL1
J 0
(-3540 2835);
DISPLAY 0.489362 (-3540 2835);
PAINT MONO (-3540 2835);
FORCEPROP 0 LASTPIN (-3550 2775) $PN AL4
J 0
(-3540 2785);
DISPLAY 0.489362 (-3540 2785);
PAINT MONO (-3540 2785);
FORCEPROP 0 LASTPIN (-3550 2725) $PN AL6
J 0
(-3540 2735);
DISPLAY 0.489362 (-3540 2735);
PAINT MONO (-3540 2735);
FORCEPROP 0 LASTPIN (-3550 2675) $PN AL8
J 0
(-3540 2685);
DISPLAY 0.489362 (-3540 2685);
PAINT MONO (-3540 2685);
FORCEPROP 0 LASTPIN (-3550 2625) $PN AL11
J 0
(-3540 2635);
DISPLAY 0.489362 (-3540 2635);
PAINT MONO (-3540 2635);
FORCEPROP 0 LASTPIN (-3550 2575) $PN AL13
J 0
(-3540 2585);
DISPLAY 0.489362 (-3540 2585);
PAINT MONO (-3540 2585);
FORCEPROP 0 LASTPIN (-3550 2525) $PN AL15
J 0
(-3540 2535);
DISPLAY 0.489362 (-3540 2535);
PAINT MONO (-3540 2535);
FORCEPROP 0 LASTPIN (-3550 2475) $PN AL18
J 0
(-3540 2485);
DISPLAY 0.489362 (-3540 2485);
PAINT MONO (-3540 2485);
FORCEPROP 0 LASTPIN (-3550 2425) $PN AL20
J 0
(-3540 2435);
DISPLAY 0.489362 (-3540 2435);
PAINT MONO (-3540 2435);
FORCEPROP 0 LASTPIN (-3550 2375) $PN AL22
J 0
(-3540 2385);
DISPLAY 0.489362 (-3540 2385);
PAINT MONO (-3540 2385);
FORCEPROP 0 LASTPIN (-3550 2325) $PN AL25
J 0
(-3540 2335);
DISPLAY 0.489362 (-3540 2335);
PAINT MONO (-3540 2335);
FORCEPROP 0 LASTPIN (-3550 2275) $PN AL28
J 0
(-3540 2285);
DISPLAY 0.489362 (-3540 2285);
PAINT MONO (-3540 2285);
FORCEPROP 0 LASTPIN (-3550 2225) $PN AL31
J 0
(-3540 2235);
DISPLAY 0.489362 (-3540 2235);
PAINT MONO (-3540 2235);
FORCEPROP 0 LASTPIN (-3550 2175) $PN AL34
J 0
(-3540 2185);
DISPLAY 0.489362 (-3540 2185);
PAINT MONO (-3540 2185);
FORCEPROP 0 LASTPIN (-3550 2125) $PN AL42
J 0
(-3540 2135);
DISPLAY 0.489362 (-3540 2135);
PAINT MONO (-3540 2135);
FORCEPROP 0 LASTPIN (-3550 2075) $PN AL45
J 0
(-3540 2085);
DISPLAY 0.489362 (-3540 2085);
PAINT MONO (-3540 2085);
FORCEPROP 0 LASTPIN (-3550 2025) $PN AL48
J 0
(-3540 2035);
DISPLAY 0.489362 (-3540 2035);
PAINT MONO (-3540 2035);
FORCEPROP 0 LASTPIN (-3550 1975) $PN AL51
J 0
(-3540 1985);
DISPLAY 0.489362 (-3540 1985);
PAINT MONO (-3540 1985);
FORCEPROP 0 LASTPIN (-3550 1925) $PN AL54
J 0
(-3540 1935);
DISPLAY 0.489362 (-3540 1935);
PAINT MONO (-3540 1935);
FORCEPROP 0 LASTPIN (-3550 1875) $PN AL56
J 0
(-3540 1885);
DISPLAY 0.489362 (-3540 1885);
PAINT MONO (-3540 1885);
FORCEPROP 0 LASTPIN (-3550 1825) $PN AL58
J 0
(-3540 1835);
DISPLAY 0.489362 (-3540 1835);
PAINT MONO (-3540 1835);
FORCEPROP 0 LASTPIN (-3550 1775) $PN AL61
J 0
(-3540 1785);
DISPLAY 0.489362 (-3540 1785);
PAINT MONO (-3540 1785);
FORCEPROP 0 LASTPIN (-3550 1725) $PN AL63
J 0
(-3540 1735);
DISPLAY 0.489362 (-3540 1735);
PAINT MONO (-3540 1735);
FORCEPROP 0 LASTPIN (-3550 1675) $PN AL65
J 0
(-3540 1685);
DISPLAY 0.489362 (-3540 1685);
PAINT MONO (-3540 1685);
FORCEPROP 0 LASTPIN (-3550 1625) $PN AL68
J 0
(-3540 1635);
DISPLAY 0.489362 (-3540 1635);
PAINT MONO (-3540 1635);
FORCEPROP 0 LASTPIN (-3550 1575) $PN AL70
J 0
(-3540 1585);
DISPLAY 0.489362 (-3540 1585);
PAINT MONO (-3540 1585);
FORCEPROP 0 LASTPIN (-3550 1525) $PN AL72
J 0
(-3540 1535);
DISPLAY 0.489362 (-3540 1535);
PAINT MONO (-3540 1535);
FORCEPROP 0 LASTPIN (-3550 1475) $PN AL75
J 0
(-3540 1485);
DISPLAY 0.489362 (-3540 1485);
PAINT MONO (-3540 1485);
FORCEPROP 0 LASTPIN (-3550 1425) $PN AM3
J 0
(-3540 1435);
DISPLAY 0.489362 (-3540 1435);
PAINT MONO (-3540 1435);
FORCEPROP 0 LASTPIN (-3550 1375) $PN AM8
J 0
(-3540 1385);
DISPLAY 0.489362 (-3540 1385);
PAINT MONO (-3540 1385);
FORCEPROP 0 LASTPIN (-3550 1325) $PN AM10
J 0
(-3540 1335);
DISPLAY 0.489362 (-3540 1335);
PAINT MONO (-3540 1335);
FORCEPROP 0 LASTPIN (-3550 1275) $PN AM15
J 0
(-3540 1285);
DISPLAY 0.489362 (-3540 1285);
PAINT MONO (-3540 1285);
FORCEPROP 0 LASTPIN (-3550 1225) $PN AM17
J 0
(-3540 1235);
DISPLAY 0.489362 (-3540 1235);
PAINT MONO (-3540 1235);
FORCEPROP 0 LASTPIN (-3550 1175) $PN AM23
J 0
(-3540 1185);
DISPLAY 0.489362 (-3540 1185);
PAINT MONO (-3540 1185);
FORCEPROP 0 LASTPIN (-3550 1125) $PN AM24
J 0
(-3540 1135);
DISPLAY 0.489362 (-3540 1135);
PAINT MONO (-3540 1135);
FORCEPROP 0 LASTPIN (-3550 1075) $PN AM25
J 0
(-3540 1085);
DISPLAY 0.489362 (-3540 1085);
PAINT MONO (-3540 1085);
FORCEPROP 0 LASTPIN (-3550 1025) $PN AM26
J 0
(-3540 1035);
DISPLAY 0.489362 (-3540 1035);
PAINT MONO (-3540 1035);
FORCEPROP 0 LASTPIN (-3550 975) $PN AM27
J 0
(-3540 985);
DISPLAY 0.489362 (-3540 985);
PAINT MONO (-3540 985);
FORCEPROP 0 LASTPIN (-3550 925) $PN AM28
J 0
(-3540 935);
DISPLAY 0.489362 (-3540 935);
PAINT MONO (-3540 935);
FORCEPROP 0 LASTPIN (-3550 875) $PN AM29
J 0
(-3540 885);
DISPLAY 0.489362 (-3540 885);
PAINT MONO (-3540 885);
FORCEPROP 0 LASTPIN (-3550 825) $PN AM30
J 0
(-3540 835);
DISPLAY 0.489362 (-3540 835);
PAINT MONO (-3540 835);
FORCEPROP 0 LASTPIN (-3550 775) $PN AM31
J 0
(-3540 785);
DISPLAY 0.489362 (-3540 785);
PAINT MONO (-3540 785);
FORCEPROP 0 LASTPIN (-3550 725) $PN AM32
J 0
(-3540 735);
DISPLAY 0.489362 (-3540 735);
PAINT MONO (-3540 735);
FORCEPROP 0 LASTPIN (-3550 675) $PN AM33
J 0
(-3540 685);
DISPLAY 0.489362 (-3540 685);
PAINT MONO (-3540 685);
FORCEPROP 0 LASTPIN (-3550 625) $PN AM34
J 0
(-3540 635);
DISPLAY 0.489362 (-3540 635);
PAINT MONO (-3540 635);
FORCEPROP 0 LASTPIN (-3550 575) $PN AM39
J 0
(-3540 585);
DISPLAY 0.489362 (-3540 585);
PAINT MONO (-3540 585);
FORCEPROP 2 LAST PART_TYPE SMLF
J 0
(-4500 6700);
DISPLAY 1.021277 (-4500 6700);
FORCEPROP 1 LAST MATERIAL IO
J 0
(-4495 6557);
DISPLAY 0.489362 (-4495 6557);
PAINT SKYBLUE (-4495 6557);
FORCEPROP 2 LAST VALUE SOCKET6096_13568-001
J 0
(-4350 6550);
DISPLAY 0.489362 (-4350 6550);
PAINT SKYBLUE (-4350 6550);
FORCEPROP 1 LAST PART_NUMBER DGA^6000030
J 0
(-4500 6650);
DISPLAY 0.489362 (-4500 6650);
PAINT SKYBLUE (-4500 6650);
FORCEPROP 1 LAST NEEDS_NO_SIZE TRUE
J 0
(-4100 3475);
DISPLAY 0.723404 (-4100 3475);
PAINT GREEN (-4100 3475);
DISPLAY INVISIBLE (-4100 3475);
FORCEPROP 1 LAST CDS_LMAN_SYM_OUTLINE -400,3050,400,-3050
J 0
(-4100 3475);
DISPLAY 0.468085 (-4100 3475);
PAINT GREEN (-4100 3475);
DISPLAY INVISIBLE (-4100 3475);
FORCEPROP 2 LAST CDS_LIB pure_quanta
J 0
(-4100 3475);
DISPLAY INVISIBLE (-4100 3475);
FORCEPROP 1 LAST PATH I22
J 0
(-4100 3475);
DISPLAY 0.723404 (-4100 3475);
PAINT GREEN (-4100 3475);
DISPLAY INVISIBLE (-4100 3475);
FORCEADD GENOA_SP5..32
(-2625 3475);
FORCEPROP 1 LAST LOCATION U25
J 0
(-3020 6600);
DISPLAY 0.489362 (-3020 6600);
PAINT SKYBLUE (-3020 6600);
FORCEPROP 0 LAST $SEC 32
J 0
(-3000 6875);
DISPLAY 0.680851 (-3000 6875);
PAINT MONO (-3000 6875);
DISPLAY INVISIBLE (-3000 6875);
FORCEPROP 0 LAST CDS_SEC 32
J 0
(-3225 6725);
DISPLAY 1.021277 (-3225 6725);
DISPLAY INVISIBLE (-3225 6725);
FORCEPROP 0 LASTPIN (-3175 6375) $PN AM42
J 2
(-3135 6385);
DISPLAY 0.489362 (-3135 6385);
PAINT MONO (-3135 6385);
FORCEPROP 0 LASTPIN (-3175 6325) $PN AM43
J 2
(-3135 6335);
DISPLAY 0.489362 (-3135 6335);
PAINT MONO (-3135 6335);
FORCEPROP 0 LASTPIN (-3175 6275) $PN AM44
J 2
(-3135 6285);
DISPLAY 0.489362 (-3135 6285);
PAINT MONO (-3135 6285);
FORCEPROP 0 LASTPIN (-3175 6225) $PN AM45
J 2
(-3135 6235);
DISPLAY 0.489362 (-3135 6235);
PAINT MONO (-3135 6235);
FORCEPROP 0 LASTPIN (-3175 6175) $PN AM46
J 2
(-3135 6185);
DISPLAY 0.489362 (-3135 6185);
PAINT MONO (-3135 6185);
FORCEPROP 0 LASTPIN (-3175 6125) $PN AM47
J 2
(-3135 6135);
DISPLAY 0.489362 (-3135 6135);
PAINT MONO (-3135 6135);
FORCEPROP 0 LASTPIN (-3175 6075) $PN AM48
J 2
(-3135 6085);
DISPLAY 0.489362 (-3135 6085);
PAINT MONO (-3135 6085);
FORCEPROP 0 LASTPIN (-3175 6025) $PN AM49
J 2
(-3135 6035);
DISPLAY 0.489362 (-3135 6035);
PAINT MONO (-3135 6035);
FORCEPROP 0 LASTPIN (-3175 5975) $PN AM50
J 2
(-3135 5985);
DISPLAY 0.489362 (-3135 5985);
PAINT MONO (-3135 5985);
FORCEPROP 0 LASTPIN (-3175 5925) $PN AM51
J 2
(-3135 5935);
DISPLAY 0.489362 (-3135 5935);
PAINT MONO (-3135 5935);
FORCEPROP 0 LASTPIN (-3175 5875) $PN AM52
J 2
(-3135 5885);
DISPLAY 0.489362 (-3135 5885);
PAINT MONO (-3135 5885);
FORCEPROP 0 LASTPIN (-3175 5825) $PN AM53
J 2
(-3135 5835);
DISPLAY 0.489362 (-3135 5835);
PAINT MONO (-3135 5835);
FORCEPROP 0 LASTPIN (-3175 5775) $PN AM59
J 2
(-3135 5785);
DISPLAY 0.489362 (-3135 5785);
PAINT MONO (-3135 5785);
FORCEPROP 0 LASTPIN (-3175 5725) $PN AM61
J 2
(-3135 5735);
DISPLAY 0.489362 (-3135 5735);
PAINT MONO (-3135 5735);
FORCEPROP 0 LASTPIN (-3175 5675) $PN AM66
J 2
(-3135 5685);
DISPLAY 0.489362 (-3135 5685);
PAINT MONO (-3135 5685);
FORCEPROP 0 LASTPIN (-3175 5625) $PN AM68
J 2
(-3135 5635);
DISPLAY 0.489362 (-3135 5635);
PAINT MONO (-3135 5635);
FORCEPROP 0 LASTPIN (-3175 5575) $PN AM73
J 2
(-3135 5585);
DISPLAY 0.489362 (-3135 5585);
PAINT MONO (-3135 5585);
FORCEPROP 0 LASTPIN (-3175 5525) $PN AN1
J 2
(-3135 5535);
DISPLAY 0.489362 (-3135 5535);
PAINT MONO (-3135 5535);
FORCEPROP 0 LASTPIN (-3175 5475) $PN AN4
J 2
(-3135 5485);
DISPLAY 0.489362 (-3135 5485);
PAINT MONO (-3135 5485);
FORCEPROP 0 LASTPIN (-3175 5425) $PN AN6
J 2
(-3135 5435);
DISPLAY 0.489362 (-3135 5435);
PAINT MONO (-3135 5435);
FORCEPROP 0 LASTPIN (-3175 5375) $PN AN8
J 2
(-3135 5385);
DISPLAY 0.489362 (-3135 5385);
PAINT MONO (-3135 5385);
FORCEPROP 0 LASTPIN (-3175 5325) $PN AN11
J 2
(-3135 5335);
DISPLAY 0.489362 (-3135 5335);
PAINT MONO (-3135 5335);
FORCEPROP 0 LASTPIN (-3175 5275) $PN AN13
J 2
(-3135 5285);
DISPLAY 0.489362 (-3135 5285);
PAINT MONO (-3135 5285);
FORCEPROP 0 LASTPIN (-3175 5225) $PN AN15
J 2
(-3135 5235);
DISPLAY 0.489362 (-3135 5235);
PAINT MONO (-3135 5235);
FORCEPROP 0 LASTPIN (-3175 5175) $PN AN18
J 2
(-3135 5185);
DISPLAY 0.489362 (-3135 5185);
PAINT MONO (-3135 5185);
FORCEPROP 0 LASTPIN (-3175 5125) $PN AN22
J 2
(-3135 5135);
DISPLAY 0.489362 (-3135 5135);
PAINT MONO (-3135 5135);
FORCEPROP 0 LASTPIN (-3175 5075) $PN AN25
J 2
(-3135 5085);
DISPLAY 0.489362 (-3135 5085);
PAINT MONO (-3135 5085);
FORCEPROP 0 LASTPIN (-3175 5025) $PN AN28
J 2
(-3135 5035);
DISPLAY 0.489362 (-3135 5035);
PAINT MONO (-3135 5035);
FORCEPROP 0 LASTPIN (-3175 4975) $PN AN31
J 2
(-3135 4985);
DISPLAY 0.489362 (-3135 4985);
PAINT MONO (-3135 4985);
FORCEPROP 0 LASTPIN (-3175 4925) $PN AN34
J 2
(-3135 4935);
DISPLAY 0.489362 (-3135 4935);
PAINT MONO (-3135 4935);
FORCEPROP 0 LASTPIN (-3175 4875) $PN AN35
J 2
(-3135 4885);
DISPLAY 0.489362 (-3135 4885);
PAINT MONO (-3135 4885);
FORCEPROP 0 LASTPIN (-3175 4825) $PN AN36
J 2
(-3135 4835);
DISPLAY 0.489362 (-3135 4835);
PAINT MONO (-3135 4835);
FORCEPROP 0 LASTPIN (-3175 4775) $PN AN40
J 2
(-3135 4785);
DISPLAY 0.489362 (-3135 4785);
PAINT MONO (-3135 4785);
FORCEPROP 0 LASTPIN (-3175 4725) $PN AN41
J 2
(-3135 4735);
DISPLAY 0.489362 (-3135 4735);
PAINT MONO (-3135 4735);
FORCEPROP 0 LASTPIN (-3175 4675) $PN AN42
J 2
(-3135 4685);
DISPLAY 0.489362 (-3135 4685);
PAINT MONO (-3135 4685);
FORCEPROP 0 LASTPIN (-3175 4625) $PN AN45
J 2
(-3135 4635);
DISPLAY 0.489362 (-3135 4635);
PAINT MONO (-3135 4635);
FORCEPROP 0 LASTPIN (-3175 4575) $PN AN48
J 2
(-3135 4585);
DISPLAY 0.489362 (-3135 4585);
PAINT MONO (-3135 4585);
FORCEPROP 0 LASTPIN (-3175 4525) $PN AN51
J 2
(-3135 4535);
DISPLAY 0.489362 (-3135 4535);
PAINT MONO (-3135 4535);
FORCEPROP 0 LASTPIN (-3175 4475) $PN AN54
J 2
(-3135 4485);
DISPLAY 0.489362 (-3135 4485);
PAINT MONO (-3135 4485);
FORCEPROP 0 LASTPIN (-3175 4425) $PN AN56
J 2
(-3135 4435);
DISPLAY 0.489362 (-3135 4435);
PAINT MONO (-3135 4435);
FORCEPROP 0 LASTPIN (-3175 4375) $PN AN58
J 2
(-3135 4385);
DISPLAY 0.489362 (-3135 4385);
PAINT MONO (-3135 4385);
FORCEPROP 0 LASTPIN (-3175 4325) $PN AN61
J 2
(-3135 4335);
DISPLAY 0.489362 (-3135 4335);
PAINT MONO (-3135 4335);
FORCEPROP 0 LASTPIN (-3175 4275) $PN AN63
J 2
(-3135 4285);
DISPLAY 0.489362 (-3135 4285);
PAINT MONO (-3135 4285);
FORCEPROP 0 LASTPIN (-3175 4225) $PN AN65
J 2
(-3135 4235);
DISPLAY 0.489362 (-3135 4235);
PAINT MONO (-3135 4235);
FORCEPROP 0 LASTPIN (-3175 4175) $PN AN68
J 2
(-3135 4185);
DISPLAY 0.489362 (-3135 4185);
PAINT MONO (-3135 4185);
FORCEPROP 0 LASTPIN (-3175 4125) $PN AN70
J 2
(-3135 4135);
DISPLAY 0.489362 (-3135 4135);
PAINT MONO (-3135 4135);
FORCEPROP 0 LASTPIN (-3175 4075) $PN AN72
J 2
(-3135 4085);
DISPLAY 0.489362 (-3135 4085);
PAINT MONO (-3135 4085);
FORCEPROP 0 LASTPIN (-3175 4025) $PN AN75
J 2
(-3135 4035);
DISPLAY 0.489362 (-3135 4035);
PAINT MONO (-3135 4035);
FORCEPROP 0 LASTPIN (-3175 3975) $PN AP3
J 2
(-3135 3985);
DISPLAY 0.489362 (-3135 3985);
PAINT MONO (-3135 3985);
FORCEPROP 0 LASTPIN (-3175 3925) $PN AP5
J 2
(-3135 3935);
DISPLAY 0.489362 (-3135 3935);
PAINT MONO (-3135 3935);
FORCEPROP 0 LASTPIN (-3175 3875) $PN AP8
J 2
(-3135 3885);
DISPLAY 0.489362 (-3135 3885);
PAINT MONO (-3135 3885);
FORCEPROP 0 LASTPIN (-3175 3825) $PN AP10
J 2
(-3135 3835);
DISPLAY 0.489362 (-3135 3835);
PAINT MONO (-3135 3835);
FORCEPROP 0 LASTPIN (-3175 3775) $PN AP12
J 2
(-3135 3785);
DISPLAY 0.489362 (-3135 3785);
PAINT MONO (-3135 3785);
FORCEPROP 0 LASTPIN (-3175 3725) $PN AP15
J 2
(-3135 3735);
DISPLAY 0.489362 (-3135 3735);
PAINT MONO (-3135 3735);
FORCEPROP 0 LASTPIN (-3175 3675) $PN AP17
J 2
(-3135 3685);
DISPLAY 0.489362 (-3135 3685);
PAINT MONO (-3135 3685);
FORCEPROP 0 LASTPIN (-3175 3625) $PN AP19
J 2
(-3135 3635);
DISPLAY 0.489362 (-3135 3635);
PAINT MONO (-3135 3635);
FORCEPROP 0 LASTPIN (-3175 3575) $PN AP22
J 2
(-3135 3585);
DISPLAY 0.489362 (-3135 3585);
PAINT MONO (-3135 3585);
FORCEPROP 0 LASTPIN (-3175 3525) $PN AP25
J 2
(-3135 3535);
DISPLAY 0.489362 (-3135 3535);
PAINT MONO (-3135 3535);
FORCEPROP 0 LASTPIN (-3175 3475) $PN AP28
J 2
(-3135 3485);
DISPLAY 0.489362 (-3135 3485);
PAINT MONO (-3135 3485);
FORCEPROP 0 LASTPIN (-3175 3425) $PN AP31
J 2
(-3135 3435);
DISPLAY 0.489362 (-3135 3435);
PAINT MONO (-3135 3435);
FORCEPROP 0 LASTPIN (-3175 3375) $PN AP34
J 2
(-3135 3385);
DISPLAY 0.489362 (-3135 3385);
PAINT MONO (-3135 3385);
FORCEPROP 0 LASTPIN (-3175 3325) $PN AP37
J 2
(-3135 3335);
DISPLAY 0.489362 (-3135 3335);
PAINT MONO (-3135 3335);
FORCEPROP 0 LASTPIN (-3175 3275) $PN AP39
J 2
(-3135 3285);
DISPLAY 0.489362 (-3135 3285);
PAINT MONO (-3135 3285);
FORCEPROP 0 LASTPIN (-3175 3225) $PN AP42
J 2
(-3135 3235);
DISPLAY 0.489362 (-3135 3235);
PAINT MONO (-3135 3235);
FORCEPROP 0 LASTPIN (-3175 3175) $PN AP45
J 2
(-3135 3185);
DISPLAY 0.489362 (-3135 3185);
PAINT MONO (-3135 3185);
FORCEPROP 0 LASTPIN (-3175 3125) $PN AP48
J 2
(-3135 3135);
DISPLAY 0.489362 (-3135 3135);
PAINT MONO (-3135 3135);
FORCEPROP 0 LASTPIN (-3175 3075) $PN AP51
J 2
(-3135 3085);
DISPLAY 0.489362 (-3135 3085);
PAINT MONO (-3135 3085);
FORCEPROP 0 LASTPIN (-3175 3025) $PN AP54
J 2
(-3135 3035);
DISPLAY 0.489362 (-3135 3035);
PAINT MONO (-3135 3035);
FORCEPROP 0 LASTPIN (-3175 2975) $PN AP57
J 2
(-3135 2985);
DISPLAY 0.489362 (-3135 2985);
PAINT MONO (-3135 2985);
FORCEPROP 0 LASTPIN (-3175 2925) $PN AP59
J 2
(-3135 2935);
DISPLAY 0.489362 (-3135 2935);
PAINT MONO (-3135 2935);
FORCEPROP 0 LASTPIN (-3175 2875) $PN AP61
J 2
(-3135 2885);
DISPLAY 0.489362 (-3135 2885);
PAINT MONO (-3135 2885);
FORCEPROP 0 LASTPIN (-3175 2825) $PN AP64
J 2
(-3135 2835);
DISPLAY 0.489362 (-3135 2835);
PAINT MONO (-3135 2835);
FORCEPROP 0 LASTPIN (-3175 2775) $PN AP66
J 2
(-3135 2785);
DISPLAY 0.489362 (-3135 2785);
PAINT MONO (-3135 2785);
FORCEPROP 0 LASTPIN (-3175 2725) $PN AP68
J 2
(-3135 2735);
DISPLAY 0.489362 (-3135 2735);
PAINT MONO (-3135 2735);
FORCEPROP 0 LASTPIN (-3175 2675) $PN AP71
J 2
(-3135 2685);
DISPLAY 0.489362 (-3135 2685);
PAINT MONO (-3135 2685);
FORCEPROP 0 LASTPIN (-3175 2625) $PN AP73
J 2
(-3135 2635);
DISPLAY 0.489362 (-3135 2635);
PAINT MONO (-3135 2635);
FORCEPROP 0 LASTPIN (-3175 2575) $PN AR1
J 2
(-3135 2585);
DISPLAY 0.489362 (-3135 2585);
PAINT MONO (-3135 2585);
FORCEPROP 0 LASTPIN (-3175 2525) $PN AR5
J 2
(-3135 2535);
DISPLAY 0.489362 (-3135 2535);
PAINT MONO (-3135 2535);
FORCEPROP 0 LASTPIN (-3175 2475) $PN AR6
J 2
(-3135 2485);
DISPLAY 0.489362 (-3135 2485);
PAINT MONO (-3135 2485);
FORCEPROP 0 LASTPIN (-3175 2425) $PN AR8
J 2
(-3135 2435);
DISPLAY 0.489362 (-3135 2435);
PAINT MONO (-3135 2435);
FORCEPROP 0 LASTPIN (-3175 2375) $PN AR9
J 2
(-3135 2385);
DISPLAY 0.489362 (-3135 2385);
PAINT MONO (-3135 2385);
FORCEPROP 0 LASTPIN (-3175 2325) $PN AR12
J 2
(-3135 2335);
DISPLAY 0.489362 (-3135 2335);
PAINT MONO (-3135 2335);
FORCEPROP 0 LASTPIN (-3175 2275) $PN AR13
J 2
(-3135 2285);
DISPLAY 0.489362 (-3135 2285);
PAINT MONO (-3135 2285);
FORCEPROP 0 LASTPIN (-3175 2225) $PN AR15
J 2
(-3135 2235);
DISPLAY 0.489362 (-3135 2235);
PAINT MONO (-3135 2235);
FORCEPROP 0 LASTPIN (-3175 2175) $PN AR16
J 2
(-3135 2185);
DISPLAY 0.489362 (-3135 2185);
PAINT MONO (-3135 2185);
FORCEPROP 0 LASTPIN (-3175 2125) $PN AR19
J 2
(-3135 2135);
DISPLAY 0.489362 (-3135 2135);
PAINT MONO (-3135 2135);
FORCEPROP 0 LASTPIN (-3175 2075) $PN AR20
J 2
(-3135 2085);
DISPLAY 0.489362 (-3135 2085);
PAINT MONO (-3135 2085);
FORCEPROP 0 LASTPIN (-3175 2025) $PN AR22
J 2
(-3135 2035);
DISPLAY 0.489362 (-3135 2035);
PAINT MONO (-3135 2035);
FORCEPROP 0 LASTPIN (-3175 1975) $PN AR24
J 2
(-3135 1985);
DISPLAY 0.489362 (-3135 1985);
PAINT MONO (-3135 1985);
FORCEPROP 0 LASTPIN (-3175 1925) $PN AR26
J 2
(-3135 1935);
DISPLAY 0.489362 (-3135 1935);
PAINT MONO (-3135 1935);
FORCEPROP 0 LASTPIN (-3175 1875) $PN AR28
J 2
(-3135 1885);
DISPLAY 0.489362 (-3135 1885);
PAINT MONO (-3135 1885);
FORCEPROP 0 LASTPIN (-3175 1825) $PN AR30
J 2
(-3135 1835);
DISPLAY 0.489362 (-3135 1835);
PAINT MONO (-3135 1835);
FORCEPROP 0 LASTPIN (-3175 1775) $PN AR32
J 2
(-3135 1785);
DISPLAY 0.489362 (-3135 1785);
PAINT MONO (-3135 1785);
FORCEPROP 0 LASTPIN (-3175 1725) $PN AR34
J 2
(-3135 1735);
DISPLAY 0.489362 (-3135 1735);
PAINT MONO (-3135 1735);
FORCEPROP 0 LASTPIN (-3175 1675) $PN AR36
J 2
(-3135 1685);
DISPLAY 0.489362 (-3135 1685);
PAINT MONO (-3135 1685);
FORCEPROP 0 LASTPIN (-3175 1625) $PN AR41
J 2
(-3135 1635);
DISPLAY 0.489362 (-3135 1635);
PAINT MONO (-3135 1635);
FORCEPROP 0 LASTPIN (-3175 1575) $PN AR43
J 2
(-3135 1585);
DISPLAY 0.489362 (-3135 1585);
PAINT MONO (-3135 1585);
FORCEPROP 0 LASTPIN (-3175 1525) $PN AR45
J 2
(-3135 1535);
DISPLAY 0.489362 (-3135 1535);
PAINT MONO (-3135 1535);
FORCEPROP 0 LASTPIN (-3175 1475) $PN AR47
J 2
(-3135 1485);
DISPLAY 0.489362 (-3135 1485);
PAINT MONO (-3135 1485);
FORCEPROP 0 LASTPIN (-3175 1425) $PN AR49
J 2
(-3135 1435);
DISPLAY 0.489362 (-3135 1435);
PAINT MONO (-3135 1435);
FORCEPROP 0 LASTPIN (-3175 1375) $PN AR51
J 2
(-3135 1385);
DISPLAY 0.489362 (-3135 1385);
PAINT MONO (-3135 1385);
FORCEPROP 0 LASTPIN (-3175 1325) $PN AR53
J 2
(-3135 1335);
DISPLAY 0.489362 (-3135 1335);
PAINT MONO (-3135 1335);
FORCEPROP 0 LASTPIN (-3175 1275) $PN AR56
J 2
(-3135 1285);
DISPLAY 0.489362 (-3135 1285);
PAINT MONO (-3135 1285);
FORCEPROP 0 LASTPIN (-3175 1225) $PN AR57
J 2
(-3135 1235);
DISPLAY 0.489362 (-3135 1235);
PAINT MONO (-3135 1235);
FORCEPROP 0 LASTPIN (-3175 1175) $PN AR60
J 2
(-3135 1185);
DISPLAY 0.489362 (-3135 1185);
PAINT MONO (-3135 1185);
FORCEPROP 0 LASTPIN (-3175 1125) $PN AR61
J 2
(-3135 1135);
DISPLAY 0.489362 (-3135 1135);
PAINT MONO (-3135 1135);
FORCEPROP 0 LASTPIN (-3175 1075) $PN AR63
J 2
(-3135 1085);
DISPLAY 0.489362 (-3135 1085);
PAINT MONO (-3135 1085);
FORCEPROP 0 LASTPIN (-3175 1025) $PN AR64
J 2
(-3135 1035);
DISPLAY 0.489362 (-3135 1035);
PAINT MONO (-3135 1035);
FORCEPROP 0 LASTPIN (-3175 975) $PN AR67
J 2
(-3135 985);
DISPLAY 0.489362 (-3135 985);
PAINT MONO (-3135 985);
FORCEPROP 0 LASTPIN (-3175 925) $PN AR68
J 2
(-3135 935);
DISPLAY 0.489362 (-3135 935);
PAINT MONO (-3135 935);
FORCEPROP 0 LASTPIN (-3175 875) $PN AR70
J 2
(-3135 885);
DISPLAY 0.489362 (-3135 885);
PAINT MONO (-3135 885);
FORCEPROP 0 LASTPIN (-3175 825) $PN AR71
J 2
(-3135 835);
DISPLAY 0.489362 (-3135 835);
PAINT MONO (-3135 835);
FORCEPROP 0 LASTPIN (-3175 775) $PN AR75
J 2
(-3135 785);
DISPLAY 0.489362 (-3135 785);
PAINT MONO (-3135 785);
FORCEPROP 0 LASTPIN (-3175 725) $PN AT3
J 2
(-3135 735);
DISPLAY 0.489362 (-3135 735);
PAINT MONO (-3135 735);
FORCEPROP 0 LASTPIN (-3175 675) $PN AT4
J 2
(-3135 685);
DISPLAY 0.489362 (-3135 685);
PAINT MONO (-3135 685);
FORCEPROP 0 LASTPIN (-3175 625) $PN AT5
J 2
(-3135 635);
DISPLAY 0.489362 (-3135 635);
PAINT MONO (-3135 635);
FORCEPROP 0 LASTPIN (-3175 575) $PN AT6
J 2
(-3135 585);
DISPLAY 0.489362 (-3135 585);
PAINT MONO (-3135 585);
FORCEPROP 0 LASTPIN (-3175 525) $PN AT8
J 2
(-3135 535);
DISPLAY 0.489362 (-3135 535);
PAINT MONO (-3135 535);
FORCEPROP 0 LASTPIN (-2075 6425) $PN AT9
J 0
(-2065 6435);
DISPLAY 0.489362 (-2065 6435);
PAINT MONO (-2065 6435);
FORCEPROP 0 LASTPIN (-2075 6375) $PN AT10
J 0
(-2065 6385);
DISPLAY 0.489362 (-2065 6385);
PAINT MONO (-2065 6385);
FORCEPROP 0 LASTPIN (-2075 6325) $PN AT12
J 0
(-2065 6335);
DISPLAY 0.489362 (-2065 6335);
PAINT MONO (-2065 6335);
FORCEPROP 0 LASTPIN (-2075 6275) $PN AT13
J 0
(-2065 6285);
DISPLAY 0.489362 (-2065 6285);
PAINT MONO (-2065 6285);
FORCEPROP 0 LASTPIN (-2075 6225) $PN AT15
J 0
(-2065 6235);
DISPLAY 0.489362 (-2065 6235);
PAINT MONO (-2065 6235);
FORCEPROP 0 LASTPIN (-2075 6175) $PN AT16
J 0
(-2065 6185);
DISPLAY 0.489362 (-2065 6185);
PAINT MONO (-2065 6185);
FORCEPROP 0 LASTPIN (-2075 6125) $PN AT17
J 0
(-2065 6135);
DISPLAY 0.489362 (-2065 6135);
PAINT MONO (-2065 6135);
FORCEPROP 0 LASTPIN (-2075 6075) $PN AT19
J 0
(-2065 6085);
DISPLAY 0.489362 (-2065 6085);
PAINT MONO (-2065 6085);
FORCEPROP 0 LASTPIN (-2075 6025) $PN AT20
J 0
(-2065 6035);
DISPLAY 0.489362 (-2065 6035);
PAINT MONO (-2065 6035);
FORCEPROP 0 LASTPIN (-2075 5975) $PN AT23
J 0
(-2065 5985);
DISPLAY 0.489362 (-2065 5985);
PAINT MONO (-2065 5985);
FORCEPROP 0 LASTPIN (-2075 5925) $PN AT25
J 0
(-2065 5935);
DISPLAY 0.489362 (-2065 5935);
PAINT MONO (-2065 5935);
FORCEPROP 0 LASTPIN (-2075 5875) $PN AT27
J 0
(-2065 5885);
DISPLAY 0.489362 (-2065 5885);
PAINT MONO (-2065 5885);
FORCEPROP 0 LASTPIN (-2075 5825) $PN AT29
J 0
(-2065 5835);
DISPLAY 0.489362 (-2065 5835);
PAINT MONO (-2065 5835);
FORCEPROP 0 LASTPIN (-2075 5775) $PN AT31
J 0
(-2065 5785);
DISPLAY 0.489362 (-2065 5785);
PAINT MONO (-2065 5785);
FORCEPROP 0 LASTPIN (-2075 5725) $PN AT33
J 0
(-2065 5735);
DISPLAY 0.489362 (-2065 5735);
PAINT MONO (-2065 5735);
FORCEPROP 0 LASTPIN (-2075 5675) $PN AT35
J 0
(-2065 5685);
DISPLAY 0.489362 (-2065 5685);
PAINT MONO (-2065 5685);
FORCEPROP 0 LASTPIN (-2075 5625) $PN AT37
J 0
(-2065 5635);
DISPLAY 0.489362 (-2065 5635);
PAINT MONO (-2065 5635);
FORCEPROP 0 LASTPIN (-2075 5575) $PN AT40
J 0
(-2065 5585);
DISPLAY 0.489362 (-2065 5585);
PAINT MONO (-2065 5585);
FORCEPROP 0 LASTPIN (-2075 5525) $PN AT42
J 0
(-2065 5535);
DISPLAY 0.489362 (-2065 5535);
PAINT MONO (-2065 5535);
FORCEPROP 0 LASTPIN (-2075 5475) $PN AT44
J 0
(-2065 5485);
DISPLAY 0.489362 (-2065 5485);
PAINT MONO (-2065 5485);
FORCEPROP 0 LASTPIN (-2075 5425) $PN AT46
J 0
(-2065 5435);
DISPLAY 0.489362 (-2065 5435);
PAINT MONO (-2065 5435);
FORCEPROP 0 LASTPIN (-2075 5375) $PN AT48
J 0
(-2065 5385);
DISPLAY 0.489362 (-2065 5385);
PAINT MONO (-2065 5385);
FORCEPROP 0 LASTPIN (-2075 5325) $PN AT50
J 0
(-2065 5335);
DISPLAY 0.489362 (-2065 5335);
PAINT MONO (-2065 5335);
FORCEPROP 0 LASTPIN (-2075 5275) $PN AT52
J 0
(-2065 5285);
DISPLAY 0.489362 (-2065 5285);
PAINT MONO (-2065 5285);
FORCEPROP 0 LASTPIN (-2075 5225) $PN AT54
J 0
(-2065 5235);
DISPLAY 0.489362 (-2065 5235);
PAINT MONO (-2065 5235);
FORCEPROP 0 LASTPIN (-2075 5175) $PN AT56
J 0
(-2065 5185);
DISPLAY 0.489362 (-2065 5185);
PAINT MONO (-2065 5185);
FORCEPROP 0 LASTPIN (-2075 5125) $PN AT57
J 0
(-2065 5135);
DISPLAY 0.489362 (-2065 5135);
PAINT MONO (-2065 5135);
FORCEPROP 0 LASTPIN (-2075 5075) $PN AT59
J 0
(-2065 5085);
DISPLAY 0.489362 (-2065 5085);
PAINT MONO (-2065 5085);
FORCEPROP 0 LASTPIN (-2075 5025) $PN AT60
J 0
(-2065 5035);
DISPLAY 0.489362 (-2065 5035);
PAINT MONO (-2065 5035);
FORCEPROP 0 LASTPIN (-2075 4975) $PN AT61
J 0
(-2065 4985);
DISPLAY 0.489362 (-2065 4985);
PAINT MONO (-2065 4985);
FORCEPROP 0 LASTPIN (-2075 4925) $PN AT63
J 0
(-2065 4935);
DISPLAY 0.489362 (-2065 4935);
PAINT MONO (-2065 4935);
FORCEPROP 0 LASTPIN (-2075 4875) $PN AT64
J 0
(-2065 4885);
DISPLAY 0.489362 (-2065 4885);
PAINT MONO (-2065 4885);
FORCEPROP 0 LASTPIN (-2075 4825) $PN AT66
J 0
(-2065 4835);
DISPLAY 0.489362 (-2065 4835);
PAINT MONO (-2065 4835);
FORCEPROP 0 LASTPIN (-2075 4775) $PN AT67
J 0
(-2065 4785);
DISPLAY 0.489362 (-2065 4785);
PAINT MONO (-2065 4785);
FORCEPROP 0 LASTPIN (-2075 4725) $PN AT68
J 0
(-2065 4735);
DISPLAY 0.489362 (-2065 4735);
PAINT MONO (-2065 4735);
FORCEPROP 0 LASTPIN (-2075 4675) $PN AT70
J 0
(-2065 4685);
DISPLAY 0.489362 (-2065 4685);
PAINT MONO (-2065 4685);
FORCEPROP 0 LASTPIN (-2075 4625) $PN AT71
J 0
(-2065 4635);
DISPLAY 0.489362 (-2065 4635);
PAINT MONO (-2065 4635);
FORCEPROP 0 LASTPIN (-2075 4575) $PN AT72
J 0
(-2065 4585);
DISPLAY 0.489362 (-2065 4585);
PAINT MONO (-2065 4585);
FORCEPROP 0 LASTPIN (-2075 4525) $PN AT73
J 0
(-2065 4535);
DISPLAY 0.489362 (-2065 4535);
PAINT MONO (-2065 4535);
FORCEPROP 0 LASTPIN (-2075 4475) $PN AU1
J 0
(-2065 4485);
DISPLAY 0.489362 (-2065 4485);
PAINT MONO (-2065 4485);
FORCEPROP 0 LASTPIN (-2075 4425) $PN AU3
J 0
(-2065 4435);
DISPLAY 0.489362 (-2065 4435);
PAINT MONO (-2065 4435);
FORCEPROP 0 LASTPIN (-2075 4375) $PN AU4
J 0
(-2065 4385);
DISPLAY 0.489362 (-2065 4385);
PAINT MONO (-2065 4385);
FORCEPROP 0 LASTPIN (-2075 4325) $PN AU6
J 0
(-2065 4335);
DISPLAY 0.489362 (-2065 4335);
PAINT MONO (-2065 4335);
FORCEPROP 0 LASTPIN (-2075 4275) $PN AU8
J 0
(-2065 4285);
DISPLAY 0.489362 (-2065 4285);
PAINT MONO (-2065 4285);
FORCEPROP 0 LASTPIN (-2075 4225) $PN AU11
J 0
(-2065 4235);
DISPLAY 0.489362 (-2065 4235);
PAINT MONO (-2065 4235);
FORCEPROP 0 LASTPIN (-2075 4175) $PN AU13
J 0
(-2065 4185);
DISPLAY 0.489362 (-2065 4185);
PAINT MONO (-2065 4185);
FORCEPROP 0 LASTPIN (-2075 4125) $PN AU15
J 0
(-2065 4135);
DISPLAY 0.489362 (-2065 4135);
PAINT MONO (-2065 4135);
FORCEPROP 0 LASTPIN (-2075 4075) $PN AU18
J 0
(-2065 4085);
DISPLAY 0.489362 (-2065 4085);
PAINT MONO (-2065 4085);
FORCEPROP 0 LASTPIN (-2075 4025) $PN AU20
J 0
(-2065 4035);
DISPLAY 0.489362 (-2065 4035);
PAINT MONO (-2065 4035);
FORCEPROP 0 LASTPIN (-2075 3975) $PN AU22
J 0
(-2065 3985);
DISPLAY 0.489362 (-2065 3985);
PAINT MONO (-2065 3985);
FORCEPROP 0 LASTPIN (-2075 3925) $PN AU24
J 0
(-2065 3935);
DISPLAY 0.489362 (-2065 3935);
PAINT MONO (-2065 3935);
FORCEPROP 0 LASTPIN (-2075 3875) $PN AU26
J 0
(-2065 3885);
DISPLAY 0.489362 (-2065 3885);
PAINT MONO (-2065 3885);
FORCEPROP 0 LASTPIN (-2075 3825) $PN AU28
J 0
(-2065 3835);
DISPLAY 0.489362 (-2065 3835);
PAINT MONO (-2065 3835);
FORCEPROP 0 LASTPIN (-2075 3775) $PN AU30
J 0
(-2065 3785);
DISPLAY 0.489362 (-2065 3785);
PAINT MONO (-2065 3785);
FORCEPROP 0 LASTPIN (-2075 3725) $PN AU32
J 0
(-2065 3735);
DISPLAY 0.489362 (-2065 3735);
PAINT MONO (-2065 3735);
FORCEPROP 0 LASTPIN (-2075 3675) $PN AU34
J 0
(-2065 3685);
DISPLAY 0.489362 (-2065 3685);
PAINT MONO (-2065 3685);
FORCEPROP 0 LASTPIN (-2075 3625) $PN AU36
J 0
(-2065 3635);
DISPLAY 0.489362 (-2065 3635);
PAINT MONO (-2065 3635);
FORCEPROP 0 LASTPIN (-2075 3575) $PN AU41
J 0
(-2065 3585);
DISPLAY 0.489362 (-2065 3585);
PAINT MONO (-2065 3585);
FORCEPROP 0 LASTPIN (-2075 3525) $PN AU43
J 0
(-2065 3535);
DISPLAY 0.489362 (-2065 3535);
PAINT MONO (-2065 3535);
FORCEPROP 0 LASTPIN (-2075 3475) $PN AU45
J 0
(-2065 3485);
DISPLAY 0.489362 (-2065 3485);
PAINT MONO (-2065 3485);
FORCEPROP 0 LASTPIN (-2075 3425) $PN AU47
J 0
(-2065 3435);
DISPLAY 0.489362 (-2065 3435);
PAINT MONO (-2065 3435);
FORCEPROP 0 LASTPIN (-2075 3375) $PN AU49
J 0
(-2065 3385);
DISPLAY 0.489362 (-2065 3385);
PAINT MONO (-2065 3385);
FORCEPROP 0 LASTPIN (-2075 3325) $PN AU51
J 0
(-2065 3335);
DISPLAY 0.489362 (-2065 3335);
PAINT MONO (-2065 3335);
FORCEPROP 0 LASTPIN (-2075 3275) $PN AU53
J 0
(-2065 3285);
DISPLAY 0.489362 (-2065 3285);
PAINT MONO (-2065 3285);
FORCEPROP 0 LASTPIN (-2075 3225) $PN AU56
J 0
(-2065 3235);
DISPLAY 0.489362 (-2065 3235);
PAINT MONO (-2065 3235);
FORCEPROP 0 LASTPIN (-2075 3175) $PN AU58
J 0
(-2065 3185);
DISPLAY 0.489362 (-2065 3185);
PAINT MONO (-2065 3185);
FORCEPROP 0 LASTPIN (-2075 3125) $PN AU61
J 0
(-2065 3135);
DISPLAY 0.489362 (-2065 3135);
PAINT MONO (-2065 3135);
FORCEPROP 0 LASTPIN (-2075 3075) $PN AU63
J 0
(-2065 3085);
DISPLAY 0.489362 (-2065 3085);
PAINT MONO (-2065 3085);
FORCEPROP 0 LASTPIN (-2075 3025) $PN AU65
J 0
(-2065 3035);
DISPLAY 0.489362 (-2065 3035);
PAINT MONO (-2065 3035);
FORCEPROP 0 LASTPIN (-2075 2975) $PN AU68
J 0
(-2065 2985);
DISPLAY 0.489362 (-2065 2985);
PAINT MONO (-2065 2985);
FORCEPROP 0 LASTPIN (-2075 2925) $PN AU70
J 0
(-2065 2935);
DISPLAY 0.489362 (-2065 2935);
PAINT MONO (-2065 2935);
FORCEPROP 0 LASTPIN (-2075 2875) $PN AU72
J 0
(-2065 2885);
DISPLAY 0.489362 (-2065 2885);
PAINT MONO (-2065 2885);
FORCEPROP 0 LASTPIN (-2075 2825) $PN AU73
J 0
(-2065 2835);
DISPLAY 0.489362 (-2065 2835);
PAINT MONO (-2065 2835);
FORCEPROP 0 LASTPIN (-2075 2775) $PN AU75
J 0
(-2065 2785);
DISPLAY 0.489362 (-2065 2785);
PAINT MONO (-2065 2785);
FORCEPROP 0 LASTPIN (-2075 2725) $PN AV3
J 0
(-2065 2735);
DISPLAY 0.489362 (-2065 2735);
PAINT MONO (-2065 2735);
FORCEPROP 0 LASTPIN (-2075 2675) $PN AV8
J 0
(-2065 2685);
DISPLAY 0.489362 (-2065 2685);
PAINT MONO (-2065 2685);
FORCEPROP 0 LASTPIN (-2075 2625) $PN AV10
J 0
(-2065 2635);
DISPLAY 0.489362 (-2065 2635);
PAINT MONO (-2065 2635);
FORCEPROP 0 LASTPIN (-2075 2575) $PN AV15
J 0
(-2065 2585);
DISPLAY 0.489362 (-2065 2585);
PAINT MONO (-2065 2585);
FORCEPROP 0 LASTPIN (-2075 2525) $PN AV17
J 0
(-2065 2535);
DISPLAY 0.489362 (-2065 2535);
PAINT MONO (-2065 2535);
FORCEPROP 0 LASTPIN (-2075 2475) $PN AV23
J 0
(-2065 2485);
DISPLAY 0.489362 (-2065 2485);
PAINT MONO (-2065 2485);
FORCEPROP 0 LASTPIN (-2075 2425) $PN AV25
J 0
(-2065 2435);
DISPLAY 0.489362 (-2065 2435);
PAINT MONO (-2065 2435);
FORCEPROP 0 LASTPIN (-2075 2375) $PN AV27
J 0
(-2065 2385);
DISPLAY 0.489362 (-2065 2385);
PAINT MONO (-2065 2385);
FORCEPROP 0 LASTPIN (-2075 2325) $PN AV29
J 0
(-2065 2335);
DISPLAY 0.489362 (-2065 2335);
PAINT MONO (-2065 2335);
FORCEPROP 0 LASTPIN (-2075 2275) $PN AV31
J 0
(-2065 2285);
DISPLAY 0.489362 (-2065 2285);
PAINT MONO (-2065 2285);
FORCEPROP 0 LASTPIN (-2075 2225) $PN AV33
J 0
(-2065 2235);
DISPLAY 0.489362 (-2065 2235);
PAINT MONO (-2065 2235);
FORCEPROP 0 LASTPIN (-2075 2175) $PN AV35
J 0
(-2065 2185);
DISPLAY 0.489362 (-2065 2185);
PAINT MONO (-2065 2185);
FORCEPROP 0 LASTPIN (-2075 2125) $PN AV37
J 0
(-2065 2135);
DISPLAY 0.489362 (-2065 2135);
PAINT MONO (-2065 2135);
FORCEPROP 0 LASTPIN (-2075 2075) $PN AV40
J 0
(-2065 2085);
DISPLAY 0.489362 (-2065 2085);
PAINT MONO (-2065 2085);
FORCEPROP 0 LASTPIN (-2075 2025) $PN AV42
J 0
(-2065 2035);
DISPLAY 0.489362 (-2065 2035);
PAINT MONO (-2065 2035);
FORCEPROP 0 LASTPIN (-2075 1975) $PN AV44
J 0
(-2065 1985);
DISPLAY 0.489362 (-2065 1985);
PAINT MONO (-2065 1985);
FORCEPROP 0 LASTPIN (-2075 1925) $PN AV46
J 0
(-2065 1935);
DISPLAY 0.489362 (-2065 1935);
PAINT MONO (-2065 1935);
FORCEPROP 0 LASTPIN (-2075 1875) $PN AV48
J 0
(-2065 1885);
DISPLAY 0.489362 (-2065 1885);
PAINT MONO (-2065 1885);
FORCEPROP 0 LASTPIN (-2075 1825) $PN AV50
J 0
(-2065 1835);
DISPLAY 0.489362 (-2065 1835);
PAINT MONO (-2065 1835);
FORCEPROP 0 LASTPIN (-2075 1775) $PN AV52
J 0
(-2065 1785);
DISPLAY 0.489362 (-2065 1785);
PAINT MONO (-2065 1785);
FORCEPROP 0 LASTPIN (-2075 1725) $PN AV54
J 0
(-2065 1735);
DISPLAY 0.489362 (-2065 1735);
PAINT MONO (-2065 1735);
FORCEPROP 0 LASTPIN (-2075 1675) $PN AV59
J 0
(-2065 1685);
DISPLAY 0.489362 (-2065 1685);
PAINT MONO (-2065 1685);
FORCEPROP 0 LASTPIN (-2075 1625) $PN AV61
J 0
(-2065 1635);
DISPLAY 0.489362 (-2065 1635);
PAINT MONO (-2065 1635);
FORCEPROP 0 LASTPIN (-2075 1575) $PN AV66
J 0
(-2065 1585);
DISPLAY 0.489362 (-2065 1585);
PAINT MONO (-2065 1585);
FORCEPROP 0 LASTPIN (-2075 1525) $PN AV68
J 0
(-2065 1535);
DISPLAY 0.489362 (-2065 1535);
PAINT MONO (-2065 1535);
FORCEPROP 0 LASTPIN (-2075 1475) $PN AV73
J 0
(-2065 1485);
DISPLAY 0.489362 (-2065 1485);
PAINT MONO (-2065 1485);
FORCEPROP 0 LASTPIN (-2075 1425) $PN AW1
J 0
(-2065 1435);
DISPLAY 0.489362 (-2065 1435);
PAINT MONO (-2065 1435);
FORCEPROP 0 LASTPIN (-2075 1375) $PN AW4
J 0
(-2065 1385);
DISPLAY 0.489362 (-2065 1385);
PAINT MONO (-2065 1385);
FORCEPROP 0 LASTPIN (-2075 1325) $PN AW6
J 0
(-2065 1335);
DISPLAY 0.489362 (-2065 1335);
PAINT MONO (-2065 1335);
FORCEPROP 0 LASTPIN (-2075 1275) $PN AW8
J 0
(-2065 1285);
DISPLAY 0.489362 (-2065 1285);
PAINT MONO (-2065 1285);
FORCEPROP 0 LASTPIN (-2075 1225) $PN AW11
J 0
(-2065 1235);
DISPLAY 0.489362 (-2065 1235);
PAINT MONO (-2065 1235);
FORCEPROP 0 LASTPIN (-2075 1175) $PN AW13
J 0
(-2065 1185);
DISPLAY 0.489362 (-2065 1185);
PAINT MONO (-2065 1185);
FORCEPROP 0 LASTPIN (-2075 1125) $PN AW15
J 0
(-2065 1135);
DISPLAY 0.489362 (-2065 1135);
PAINT MONO (-2065 1135);
FORCEPROP 0 LASTPIN (-2075 1075) $PN AW18
J 0
(-2065 1085);
DISPLAY 0.489362 (-2065 1085);
PAINT MONO (-2065 1085);
FORCEPROP 0 LASTPIN (-2075 1025) $PN AW20
J 0
(-2065 1035);
DISPLAY 0.489362 (-2065 1035);
PAINT MONO (-2065 1035);
FORCEPROP 0 LASTPIN (-2075 975) $PN AW22
J 0
(-2065 985);
DISPLAY 0.489362 (-2065 985);
PAINT MONO (-2065 985);
FORCEPROP 0 LASTPIN (-2075 925) $PN AW24
J 0
(-2065 935);
DISPLAY 0.489362 (-2065 935);
PAINT MONO (-2065 935);
FORCEPROP 0 LASTPIN (-2075 875) $PN AW26
J 0
(-2065 885);
DISPLAY 0.489362 (-2065 885);
PAINT MONO (-2065 885);
FORCEPROP 0 LASTPIN (-2075 825) $PN AW28
J 0
(-2065 835);
DISPLAY 0.489362 (-2065 835);
PAINT MONO (-2065 835);
FORCEPROP 0 LASTPIN (-2075 775) $PN AW49
J 0
(-2065 785);
DISPLAY 0.489362 (-2065 785);
PAINT MONO (-2065 785);
FORCEPROP 0 LASTPIN (-2075 725) $PN AW51
J 0
(-2065 735);
DISPLAY 0.489362 (-2065 735);
PAINT MONO (-2065 735);
FORCEPROP 0 LASTPIN (-2075 675) $PN AW53
J 0
(-2065 685);
DISPLAY 0.489362 (-2065 685);
PAINT MONO (-2065 685);
FORCEPROP 0 LASTPIN (-2075 625) $PN AW56
J 0
(-2065 635);
DISPLAY 0.489362 (-2065 635);
PAINT MONO (-2065 635);
FORCEPROP 0 LASTPIN (-2075 575) $PN AW58
J 0
(-2065 585);
DISPLAY 0.489362 (-2065 585);
PAINT MONO (-2065 585);
FORCEPROP 0 LASTPIN (-2075 525) $PN AW61
J 0
(-2065 535);
DISPLAY 0.489362 (-2065 535);
PAINT MONO (-2065 535);
FORCEPROP 2 LAST PART_TYPE SMLF
J 0
(-3025 6700);
DISPLAY 1.021277 (-3025 6700);
FORCEPROP 1 LAST MATERIAL IO
J 0
(-3020 6557);
DISPLAY 0.489362 (-3020 6557);
PAINT SKYBLUE (-3020 6557);
FORCEPROP 2 LAST VALUE SOCKET6096_13568-001
J 0
(-2900 6550);
DISPLAY 0.489362 (-2900 6550);
PAINT SKYBLUE (-2900 6550);
FORCEPROP 1 LAST PART_NUMBER DGA^6000030
J 0
(-3020 6650);
DISPLAY 0.489362 (-3020 6650);
PAINT SKYBLUE (-3020 6650);
FORCEPROP 1 LAST NEEDS_NO_SIZE TRUE
J 0
(-2625 3475);
DISPLAY 0.723404 (-2625 3475);
PAINT GREEN (-2625 3475);
DISPLAY INVISIBLE (-2625 3475);
FORCEPROP 1 LAST CDS_LMAN_SYM_OUTLINE -400,3050,400,-3050
J 0
(-2625 3475);
DISPLAY 0.468085 (-2625 3475);
PAINT GREEN (-2625 3475);
DISPLAY INVISIBLE (-2625 3475);
FORCEPROP 2 LAST CDS_LIB pure_quanta
J 0
(-2625 3475);
DISPLAY INVISIBLE (-2625 3475);
FORCEPROP 1 LAST PATH I23
J 0
(-2625 3475);
DISPLAY 0.723404 (-2625 3475);
PAINT GREEN (-2625 3475);
DISPLAY INVISIBLE (-2625 3475);
FORCEADD GENOA_SP5..33
(-1000 3475);
FORCEPROP 1 LAST LOCATION U25
J 0
(-1395 6600);
DISPLAY 0.489362 (-1395 6600);
PAINT SKYBLUE (-1395 6600);
FORCEPROP 0 LAST $SEC 33
J 0
(-1375 6875);
DISPLAY 0.680851 (-1375 6875);
PAINT MONO (-1375 6875);
DISPLAY INVISIBLE (-1375 6875);
FORCEPROP 0 LAST CDS_SEC 33
J 0
(-1575 6700);
DISPLAY 1.021277 (-1575 6700);
DISPLAY INVISIBLE (-1575 6700);
FORCEPROP 0 LASTPIN (-1550 6425) $PN AW63
J 2
(-1510 6435);
DISPLAY 0.489362 (-1510 6435);
PAINT MONO (-1510 6435);
FORCEPROP 0 LASTPIN (-1550 6375) $PN AW65
J 2
(-1510 6385);
DISPLAY 0.489362 (-1510 6385);
PAINT MONO (-1510 6385);
FORCEPROP 0 LASTPIN (-1550 6325) $PN AW68
J 2
(-1510 6335);
DISPLAY 0.489362 (-1510 6335);
PAINT MONO (-1510 6335);
FORCEPROP 0 LASTPIN (-1550 6275) $PN AW70
J 2
(-1510 6285);
DISPLAY 0.489362 (-1510 6285);
PAINT MONO (-1510 6285);
FORCEPROP 0 LASTPIN (-1550 6225) $PN AW72
J 2
(-1510 6235);
DISPLAY 0.489362 (-1510 6235);
PAINT MONO (-1510 6235);
FORCEPROP 0 LASTPIN (-1550 6175) $PN AW75
J 2
(-1510 6185);
DISPLAY 0.489362 (-1510 6185);
PAINT MONO (-1510 6185);
FORCEPROP 0 LASTPIN (-1550 6125) $PN AY3
J 2
(-1510 6135);
DISPLAY 0.489362 (-1510 6135);
PAINT MONO (-1510 6135);
FORCEPROP 0 LASTPIN (-1550 6075) $PN AY5
J 2
(-1510 6085);
DISPLAY 0.489362 (-1510 6085);
PAINT MONO (-1510 6085);
FORCEPROP 0 LASTPIN (-1550 6025) $PN AY8
J 2
(-1510 6035);
DISPLAY 0.489362 (-1510 6035);
PAINT MONO (-1510 6035);
FORCEPROP 0 LASTPIN (-1550 5975) $PN AY10
J 2
(-1510 5985);
DISPLAY 0.489362 (-1510 5985);
PAINT MONO (-1510 5985);
FORCEPROP 0 LASTPIN (-1550 5925) $PN AY12
J 2
(-1510 5935);
DISPLAY 0.489362 (-1510 5935);
PAINT MONO (-1510 5935);
FORCEPROP 0 LASTPIN (-1550 5875) $PN AY15
J 2
(-1510 5885);
DISPLAY 0.489362 (-1510 5885);
PAINT MONO (-1510 5885);
FORCEPROP 0 LASTPIN (-1550 5825) $PN AY17
J 2
(-1510 5835);
DISPLAY 0.489362 (-1510 5835);
PAINT MONO (-1510 5835);
FORCEPROP 0 LASTPIN (-1550 5775) $PN AY19
J 2
(-1510 5785);
DISPLAY 0.489362 (-1510 5785);
PAINT MONO (-1510 5785);
FORCEPROP 0 LASTPIN (-1550 5725) $PN AY23
J 2
(-1510 5735);
DISPLAY 0.489362 (-1510 5735);
PAINT MONO (-1510 5735);
FORCEPROP 0 LASTPIN (-1550 5675) $PN AY25
J 2
(-1510 5685);
DISPLAY 0.489362 (-1510 5685);
PAINT MONO (-1510 5685);
FORCEPROP 0 LASTPIN (-1550 5625) $PN AY27
J 2
(-1510 5635);
DISPLAY 0.489362 (-1510 5635);
PAINT MONO (-1510 5635);
FORCEPROP 0 LASTPIN (-1550 5575) $PN AY48
J 2
(-1510 5585);
DISPLAY 0.489362 (-1510 5585);
PAINT MONO (-1510 5585);
FORCEPROP 0 LASTPIN (-1550 5525) $PN AY50
J 2
(-1510 5535);
DISPLAY 0.489362 (-1510 5535);
PAINT MONO (-1510 5535);
FORCEPROP 0 LASTPIN (-1550 5475) $PN AY52
J 2
(-1510 5485);
DISPLAY 0.489362 (-1510 5485);
PAINT MONO (-1510 5485);
FORCEPROP 0 LASTPIN (-1550 5425) $PN AY54
J 2
(-1510 5435);
DISPLAY 0.489362 (-1510 5435);
PAINT MONO (-1510 5435);
FORCEPROP 0 LASTPIN (-1550 5375) $PN AY57
J 2
(-1510 5385);
DISPLAY 0.489362 (-1510 5385);
PAINT MONO (-1510 5385);
FORCEPROP 0 LASTPIN (-1550 5325) $PN AY59
J 2
(-1510 5335);
DISPLAY 0.489362 (-1510 5335);
PAINT MONO (-1510 5335);
FORCEPROP 0 LASTPIN (-1550 5275) $PN AY61
J 2
(-1510 5285);
DISPLAY 0.489362 (-1510 5285);
PAINT MONO (-1510 5285);
FORCEPROP 0 LASTPIN (-1550 5225) $PN AY64
J 2
(-1510 5235);
DISPLAY 0.489362 (-1510 5235);
PAINT MONO (-1510 5235);
FORCEPROP 0 LASTPIN (-1550 5175) $PN AY66
J 2
(-1510 5185);
DISPLAY 0.489362 (-1510 5185);
PAINT MONO (-1510 5185);
FORCEPROP 0 LASTPIN (-1550 5125) $PN AY68
J 2
(-1510 5135);
DISPLAY 0.489362 (-1510 5135);
PAINT MONO (-1510 5135);
FORCEPROP 0 LASTPIN (-1550 5075) $PN AY71
J 2
(-1510 5085);
DISPLAY 0.489362 (-1510 5085);
PAINT MONO (-1510 5085);
FORCEPROP 0 LASTPIN (-1550 5025) $PN AY73
J 2
(-1510 5035);
DISPLAY 0.489362 (-1510 5035);
PAINT MONO (-1510 5035);
FORCEPROP 0 LASTPIN (-1550 4975) $PN BA1
J 2
(-1510 4985);
DISPLAY 0.489362 (-1510 4985);
PAINT MONO (-1510 4985);
FORCEPROP 0 LASTPIN (-1550 4925) $PN BA6
J 2
(-1510 4935);
DISPLAY 0.489362 (-1510 4935);
PAINT MONO (-1510 4935);
FORCEPROP 0 LASTPIN (-1550 4875) $PN BA8
J 2
(-1510 4885);
DISPLAY 0.489362 (-1510 4885);
PAINT MONO (-1510 4885);
FORCEPROP 0 LASTPIN (-1550 4825) $PN BA13
J 2
(-1510 4835);
DISPLAY 0.489362 (-1510 4835);
PAINT MONO (-1510 4835);
FORCEPROP 0 LASTPIN (-1550 4775) $PN BA15
J 2
(-1510 4785);
DISPLAY 0.489362 (-1510 4785);
PAINT MONO (-1510 4785);
FORCEPROP 0 LASTPIN (-1550 4725) $PN BA20
J 2
(-1510 4735);
DISPLAY 0.489362 (-1510 4735);
PAINT MONO (-1510 4735);
FORCEPROP 0 LASTPIN (-1550 4675) $PN BA22
J 2
(-1510 4685);
DISPLAY 0.489362 (-1510 4685);
PAINT MONO (-1510 4685);
FORCEPROP 0 LASTPIN (-1550 4625) $PN BA24
J 2
(-1510 4635);
DISPLAY 0.489362 (-1510 4635);
PAINT MONO (-1510 4635);
FORCEPROP 0 LASTPIN (-1550 4575) $PN BA26
J 2
(-1510 4585);
DISPLAY 0.489362 (-1510 4585);
PAINT MONO (-1510 4585);
FORCEPROP 0 LASTPIN (-1550 4525) $PN BA28
J 2
(-1510 4535);
DISPLAY 0.489362 (-1510 4535);
PAINT MONO (-1510 4535);
FORCEPROP 0 LASTPIN (-1550 4475) $PN BA49
J 2
(-1510 4485);
DISPLAY 0.489362 (-1510 4485);
PAINT MONO (-1510 4485);
FORCEPROP 0 LASTPIN (-1550 4425) $PN BA51
J 2
(-1510 4435);
DISPLAY 0.489362 (-1510 4435);
PAINT MONO (-1510 4435);
FORCEPROP 0 LASTPIN (-1550 4375) $PN BA53
J 2
(-1510 4385);
DISPLAY 0.489362 (-1510 4385);
PAINT MONO (-1510 4385);
FORCEPROP 0 LASTPIN (-1550 4325) $PN BA56
J 2
(-1510 4335);
DISPLAY 0.489362 (-1510 4335);
PAINT MONO (-1510 4335);
FORCEPROP 0 LASTPIN (-1550 4275) $PN BA61
J 2
(-1510 4285);
DISPLAY 0.489362 (-1510 4285);
PAINT MONO (-1510 4285);
FORCEPROP 0 LASTPIN (-1550 4225) $PN BA63
J 2
(-1510 4235);
DISPLAY 0.489362 (-1510 4235);
PAINT MONO (-1510 4235);
FORCEPROP 0 LASTPIN (-1550 4175) $PN BA68
J 2
(-1510 4185);
DISPLAY 0.489362 (-1510 4185);
PAINT MONO (-1510 4185);
FORCEPROP 0 LASTPIN (-1550 4125) $PN BA70
J 2
(-1510 4135);
DISPLAY 0.489362 (-1510 4135);
PAINT MONO (-1510 4135);
FORCEPROP 0 LASTPIN (-1550 4075) $PN BA75
J 2
(-1510 4085);
DISPLAY 0.489362 (-1510 4085);
PAINT MONO (-1510 4085);
FORCEPROP 0 LASTPIN (-1550 4025) $PN BB3
J 2
(-1510 4035);
DISPLAY 0.489362 (-1510 4035);
PAINT MONO (-1510 4035);
FORCEPROP 0 LASTPIN (-1550 3975) $PN BB5
J 2
(-1510 3985);
DISPLAY 0.489362 (-1510 3985);
PAINT MONO (-1510 3985);
FORCEPROP 0 LASTPIN (-1550 3925) $PN BB8
J 2
(-1510 3935);
DISPLAY 0.489362 (-1510 3935);
PAINT MONO (-1510 3935);
FORCEPROP 0 LASTPIN (-1550 3875) $PN BB10
J 2
(-1510 3885);
DISPLAY 0.489362 (-1510 3885);
PAINT MONO (-1510 3885);
FORCEPROP 0 LASTPIN (-1550 3825) $PN BB12
J 2
(-1510 3835);
DISPLAY 0.489362 (-1510 3835);
PAINT MONO (-1510 3835);
FORCEPROP 0 LASTPIN (-1550 3775) $PN BB15
J 2
(-1510 3785);
DISPLAY 0.489362 (-1510 3785);
PAINT MONO (-1510 3785);
FORCEPROP 0 LASTPIN (-1550 3725) $PN BB17
J 2
(-1510 3735);
DISPLAY 0.489362 (-1510 3735);
PAINT MONO (-1510 3735);
FORCEPROP 0 LASTPIN (-1550 3675) $PN BB19
J 2
(-1510 3685);
DISPLAY 0.489362 (-1510 3685);
PAINT MONO (-1510 3685);
FORCEPROP 0 LASTPIN (-1550 3625) $PN BB23
J 2
(-1510 3635);
DISPLAY 0.489362 (-1510 3635);
PAINT MONO (-1510 3635);
FORCEPROP 0 LASTPIN (-1550 3575) $PN BB25
J 2
(-1510 3585);
DISPLAY 0.489362 (-1510 3585);
PAINT MONO (-1510 3585);
FORCEPROP 0 LASTPIN (-1550 3525) $PN BB27
J 2
(-1510 3535);
DISPLAY 0.489362 (-1510 3535);
PAINT MONO (-1510 3535);
FORCEPROP 0 LASTPIN (-1550 3475) $PN BB48
J 2
(-1510 3485);
DISPLAY 0.489362 (-1510 3485);
PAINT MONO (-1510 3485);
FORCEPROP 0 LASTPIN (-1550 3425) $PN BB50
J 2
(-1510 3435);
DISPLAY 0.489362 (-1510 3435);
PAINT MONO (-1510 3435);
FORCEPROP 0 LASTPIN (-1550 3375) $PN BB52
J 2
(-1510 3385);
DISPLAY 0.489362 (-1510 3385);
PAINT MONO (-1510 3385);
FORCEPROP 0 LASTPIN (-1550 3325) $PN BB54
J 2
(-1510 3335);
DISPLAY 0.489362 (-1510 3335);
PAINT MONO (-1510 3335);
FORCEPROP 0 LASTPIN (-1550 3275) $PN BB57
J 2
(-1510 3285);
DISPLAY 0.489362 (-1510 3285);
PAINT MONO (-1510 3285);
FORCEPROP 0 LASTPIN (-1550 3225) $PN BB59
J 2
(-1510 3235);
DISPLAY 0.489362 (-1510 3235);
PAINT MONO (-1510 3235);
FORCEPROP 0 LASTPIN (-1550 3175) $PN BB61
J 2
(-1510 3185);
DISPLAY 0.489362 (-1510 3185);
PAINT MONO (-1510 3185);
FORCEPROP 0 LASTPIN (-1550 3125) $PN BB64
J 2
(-1510 3135);
DISPLAY 0.489362 (-1510 3135);
PAINT MONO (-1510 3135);
FORCEPROP 0 LASTPIN (-1550 3075) $PN BB66
J 2
(-1510 3085);
DISPLAY 0.489362 (-1510 3085);
PAINT MONO (-1510 3085);
FORCEPROP 0 LASTPIN (-1550 3025) $PN BB68
J 2
(-1510 3035);
DISPLAY 0.489362 (-1510 3035);
PAINT MONO (-1510 3035);
FORCEPROP 0 LASTPIN (-1550 2975) $PN BB71
J 2
(-1510 2985);
DISPLAY 0.489362 (-1510 2985);
PAINT MONO (-1510 2985);
FORCEPROP 0 LASTPIN (-1550 2925) $PN BB73
J 2
(-1510 2935);
DISPLAY 0.489362 (-1510 2935);
PAINT MONO (-1510 2935);
FORCEPROP 0 LASTPIN (-1550 2875) $PN BC1
J 2
(-1510 2885);
DISPLAY 0.489362 (-1510 2885);
PAINT MONO (-1510 2885);
FORCEPROP 0 LASTPIN (-1550 2825) $PN BC4
J 2
(-1510 2835);
DISPLAY 0.489362 (-1510 2835);
PAINT MONO (-1510 2835);
FORCEPROP 0 LASTPIN (-1550 2775) $PN BC6
J 2
(-1510 2785);
DISPLAY 0.489362 (-1510 2785);
PAINT MONO (-1510 2785);
FORCEPROP 0 LASTPIN (-1550 2725) $PN BC8
J 2
(-1510 2735);
DISPLAY 0.489362 (-1510 2735);
PAINT MONO (-1510 2735);
FORCEPROP 0 LASTPIN (-1550 2675) $PN BC11
J 2
(-1510 2685);
DISPLAY 0.489362 (-1510 2685);
PAINT MONO (-1510 2685);
FORCEPROP 0 LASTPIN (-1550 2625) $PN BC13
J 2
(-1510 2635);
DISPLAY 0.489362 (-1510 2635);
PAINT MONO (-1510 2635);
FORCEPROP 0 LASTPIN (-1550 2575) $PN BC15
J 2
(-1510 2585);
DISPLAY 0.489362 (-1510 2585);
PAINT MONO (-1510 2585);
FORCEPROP 0 LASTPIN (-1550 2525) $PN BC18
J 2
(-1510 2535);
DISPLAY 0.489362 (-1510 2535);
PAINT MONO (-1510 2535);
FORCEPROP 0 LASTPIN (-1550 2475) $PN BC20
J 2
(-1510 2485);
DISPLAY 0.489362 (-1510 2485);
PAINT MONO (-1510 2485);
FORCEPROP 0 LASTPIN (-1550 2425) $PN BC22
J 2
(-1510 2435);
DISPLAY 0.489362 (-1510 2435);
PAINT MONO (-1510 2435);
FORCEPROP 0 LASTPIN (-1550 2375) $PN BC24
J 2
(-1510 2385);
DISPLAY 0.489362 (-1510 2385);
PAINT MONO (-1510 2385);
FORCEPROP 0 LASTPIN (-1550 2325) $PN BC26
J 2
(-1510 2335);
DISPLAY 0.489362 (-1510 2335);
PAINT MONO (-1510 2335);
FORCEPROP 0 LASTPIN (-1550 2275) $PN BC28
J 2
(-1510 2285);
DISPLAY 0.489362 (-1510 2285);
PAINT MONO (-1510 2285);
FORCEPROP 0 LASTPIN (-1550 2225) $PN BC49
J 2
(-1510 2235);
DISPLAY 0.489362 (-1510 2235);
PAINT MONO (-1510 2235);
FORCEPROP 0 LASTPIN (-1550 2175) $PN BC50
J 2
(-1510 2185);
DISPLAY 0.489362 (-1510 2185);
PAINT MONO (-1510 2185);
FORCEPROP 0 LASTPIN (-1550 2125) $PN BC51
J 2
(-1510 2135);
DISPLAY 0.489362 (-1510 2135);
PAINT MONO (-1510 2135);
FORCEPROP 0 LASTPIN (-1550 2075) $PN BC53
J 2
(-1510 2085);
DISPLAY 0.489362 (-1510 2085);
PAINT MONO (-1510 2085);
FORCEPROP 0 LASTPIN (-1550 2025) $PN BC56
J 2
(-1510 2035);
DISPLAY 0.489362 (-1510 2035);
PAINT MONO (-1510 2035);
FORCEPROP 0 LASTPIN (-1550 1975) $PN BC58
J 2
(-1510 1985);
DISPLAY 0.489362 (-1510 1985);
PAINT MONO (-1510 1985);
FORCEPROP 0 LASTPIN (-1550 1925) $PN BC61
J 2
(-1510 1935);
DISPLAY 0.489362 (-1510 1935);
PAINT MONO (-1510 1935);
FORCEPROP 0 LASTPIN (-1550 1875) $PN BC63
J 2
(-1510 1885);
DISPLAY 0.489362 (-1510 1885);
PAINT MONO (-1510 1885);
FORCEPROP 0 LASTPIN (-1550 1825) $PN BC65
J 2
(-1510 1835);
DISPLAY 0.489362 (-1510 1835);
PAINT MONO (-1510 1835);
FORCEPROP 0 LASTPIN (-1550 1775) $PN BC68
J 2
(-1510 1785);
DISPLAY 0.489362 (-1510 1785);
PAINT MONO (-1510 1785);
FORCEPROP 0 LASTPIN (-1550 1725) $PN BC70
J 2
(-1510 1735);
DISPLAY 0.489362 (-1510 1735);
PAINT MONO (-1510 1735);
FORCEPROP 0 LASTPIN (-1550 1675) $PN BC72
J 2
(-1510 1685);
DISPLAY 0.489362 (-1510 1685);
PAINT MONO (-1510 1685);
FORCEPROP 0 LASTPIN (-1550 1625) $PN BC75
J 2
(-1510 1635);
DISPLAY 0.489362 (-1510 1635);
PAINT MONO (-1510 1635);
FORCEPROP 0 LASTPIN (-1550 1575) $PN BD3
J 2
(-1510 1585);
DISPLAY 0.489362 (-1510 1585);
PAINT MONO (-1510 1585);
FORCEPROP 0 LASTPIN (-1550 1525) $PN BD8
J 2
(-1510 1535);
DISPLAY 0.489362 (-1510 1535);
PAINT MONO (-1510 1535);
FORCEPROP 0 LASTPIN (-1550 1475) $PN BD10
J 2
(-1510 1485);
DISPLAY 0.489362 (-1510 1485);
PAINT MONO (-1510 1485);
FORCEPROP 0 LASTPIN (-1550 1425) $PN BD15
J 2
(-1510 1435);
DISPLAY 0.489362 (-1510 1435);
PAINT MONO (-1510 1435);
FORCEPROP 0 LASTPIN (-1550 1375) $PN BD17
J 2
(-1510 1385);
DISPLAY 0.489362 (-1510 1385);
PAINT MONO (-1510 1385);
FORCEPROP 0 LASTPIN (-1550 1325) $PN BD23
J 2
(-1510 1335);
DISPLAY 0.489362 (-1510 1335);
PAINT MONO (-1510 1335);
FORCEPROP 0 LASTPIN (-1550 1275) $PN BD25
J 2
(-1510 1285);
DISPLAY 0.489362 (-1510 1285);
PAINT MONO (-1510 1285);
FORCEPROP 0 LASTPIN (-1550 1225) $PN BD27
J 2
(-1510 1235);
DISPLAY 0.489362 (-1510 1235);
PAINT MONO (-1510 1235);
FORCEPROP 0 LASTPIN (-1550 1175) $PN BD49
J 2
(-1510 1185);
DISPLAY 0.489362 (-1510 1185);
PAINT MONO (-1510 1185);
FORCEPROP 0 LASTPIN (-1550 1125) $PN BD51
J 2
(-1510 1135);
DISPLAY 0.489362 (-1510 1135);
PAINT MONO (-1510 1135);
FORCEPROP 0 LASTPIN (-1550 1075) $PN BD53
J 2
(-1510 1085);
DISPLAY 0.489362 (-1510 1085);
PAINT MONO (-1510 1085);
FORCEPROP 0 LASTPIN (-1550 1025) $PN BD57
J 2
(-1510 1035);
DISPLAY 0.489362 (-1510 1035);
PAINT MONO (-1510 1035);
FORCEPROP 0 LASTPIN (-1550 975) $PN BD59
J 2
(-1510 985);
DISPLAY 0.489362 (-1510 985);
PAINT MONO (-1510 985);
FORCEPROP 0 LASTPIN (-1550 925) $PN BD61
J 2
(-1510 935);
DISPLAY 0.489362 (-1510 935);
PAINT MONO (-1510 935);
FORCEPROP 0 LASTPIN (-1550 875) $PN BD64
J 2
(-1510 885);
DISPLAY 0.489362 (-1510 885);
PAINT MONO (-1510 885);
FORCEPROP 0 LASTPIN (-1550 825) $PN BD66
J 2
(-1510 835);
DISPLAY 0.489362 (-1510 835);
PAINT MONO (-1510 835);
FORCEPROP 0 LASTPIN (-1550 775) $PN BD68
J 2
(-1510 785);
DISPLAY 0.489362 (-1510 785);
PAINT MONO (-1510 785);
FORCEPROP 0 LASTPIN (-1550 725) $PN BD71
J 2
(-1510 735);
DISPLAY 0.489362 (-1510 735);
PAINT MONO (-1510 735);
FORCEPROP 0 LASTPIN (-1550 675) $PN BD73
J 2
(-1510 685);
DISPLAY 0.489362 (-1510 685);
PAINT MONO (-1510 685);
FORCEPROP 0 LASTPIN (-1550 625) $PN BF3
J 2
(-1510 635);
DISPLAY 0.489362 (-1510 635);
PAINT MONO (-1510 635);
FORCEPROP 0 LASTPIN (-1550 575) $PN BF5
J 2
(-1510 585);
DISPLAY 0.489362 (-1510 585);
PAINT MONO (-1510 585);
FORCEPROP 0 LASTPIN (-1550 525) $PN BF8
J 2
(-1510 535);
DISPLAY 0.489362 (-1510 535);
PAINT MONO (-1510 535);
FORCEPROP 0 LASTPIN (-450 6425) $PN BF10
J 0
(-440 6435);
DISPLAY 0.489362 (-440 6435);
PAINT MONO (-440 6435);
FORCEPROP 0 LASTPIN (-450 6375) $PN BF12
J 0
(-440 6385);
DISPLAY 0.489362 (-440 6385);
PAINT MONO (-440 6385);
FORCEPROP 0 LASTPIN (-450 6325) $PN BF15
J 0
(-440 6335);
DISPLAY 0.489362 (-440 6335);
PAINT MONO (-440 6335);
FORCEPROP 0 LASTPIN (-450 6275) $PN BF17
J 0
(-440 6285);
DISPLAY 0.489362 (-440 6285);
PAINT MONO (-440 6285);
FORCEPROP 0 LASTPIN (-450 6225) $PN BF19
J 0
(-440 6235);
DISPLAY 0.489362 (-440 6235);
PAINT MONO (-440 6235);
FORCEPROP 0 LASTPIN (-450 6175) $PN BF22
J 0
(-440 6185);
DISPLAY 0.489362 (-440 6185);
PAINT MONO (-440 6185);
FORCEPROP 0 LASTPIN (-450 6125) $PN BF24
J 0
(-440 6135);
DISPLAY 0.489362 (-440 6135);
PAINT MONO (-440 6135);
FORCEPROP 0 LASTPIN (-450 6075) $PN BF26
J 0
(-440 6085);
DISPLAY 0.489362 (-440 6085);
PAINT MONO (-440 6085);
FORCEPROP 0 LASTPIN (-450 6025) $PN BF28
J 0
(-440 6035);
DISPLAY 0.489362 (-440 6035);
PAINT MONO (-440 6035);
FORCEPROP 0 LASTPIN (-450 5975) $PN BF49
J 0
(-440 5985);
DISPLAY 0.489362 (-440 5985);
PAINT MONO (-440 5985);
FORCEPROP 0 LASTPIN (-450 5925) $PN BF50
J 0
(-440 5935);
DISPLAY 0.489362 (-440 5935);
PAINT MONO (-440 5935);
FORCEPROP 0 LASTPIN (-450 5875) $PN BF52
J 0
(-440 5885);
DISPLAY 0.489362 (-440 5885);
PAINT MONO (-440 5885);
FORCEPROP 0 LASTPIN (-450 5825) $PN BF54
J 0
(-440 5835);
DISPLAY 0.489362 (-440 5835);
PAINT MONO (-440 5835);
FORCEPROP 0 LASTPIN (-450 5775) $PN BF59
J 0
(-440 5785);
DISPLAY 0.489362 (-440 5785);
PAINT MONO (-440 5785);
FORCEPROP 0 LASTPIN (-450 5725) $PN BF61
J 0
(-440 5735);
DISPLAY 0.489362 (-440 5735);
PAINT MONO (-440 5735);
FORCEPROP 0 LASTPIN (-450 5675) $PN BF66
J 0
(-440 5685);
DISPLAY 0.489362 (-440 5685);
PAINT MONO (-440 5685);
FORCEPROP 0 LASTPIN (-450 5625) $PN BF68
J 0
(-440 5635);
DISPLAY 0.489362 (-440 5635);
PAINT MONO (-440 5635);
FORCEPROP 0 LASTPIN (-450 5575) $PN BF73
J 0
(-440 5585);
DISPLAY 0.489362 (-440 5585);
PAINT MONO (-440 5585);
FORCEPROP 0 LASTPIN (-450 5525) $PN BG1
J 0
(-440 5535);
DISPLAY 0.489362 (-440 5535);
PAINT MONO (-440 5535);
FORCEPROP 0 LASTPIN (-450 5475) $PN BG4
J 0
(-440 5485);
DISPLAY 0.489362 (-440 5485);
PAINT MONO (-440 5485);
FORCEPROP 0 LASTPIN (-450 5425) $PN BG6
J 0
(-440 5435);
DISPLAY 0.489362 (-440 5435);
PAINT MONO (-440 5435);
FORCEPROP 0 LASTPIN (-450 5375) $PN BG8
J 0
(-440 5385);
DISPLAY 0.489362 (-440 5385);
PAINT MONO (-440 5385);
FORCEPROP 0 LASTPIN (-450 5325) $PN BG11
J 0
(-440 5335);
DISPLAY 0.489362 (-440 5335);
PAINT MONO (-440 5335);
FORCEPROP 0 LASTPIN (-450 5275) $PN BG13
J 0
(-440 5285);
DISPLAY 0.489362 (-440 5285);
PAINT MONO (-440 5285);
FORCEPROP 0 LASTPIN (-450 5225) $PN BG15
J 0
(-440 5235);
DISPLAY 0.489362 (-440 5235);
PAINT MONO (-440 5235);
FORCEPROP 0 LASTPIN (-450 5175) $PN BG18
J 0
(-440 5185);
DISPLAY 0.489362 (-440 5185);
PAINT MONO (-440 5185);
FORCEPROP 0 LASTPIN (-450 5125) $PN BG20
J 0
(-440 5135);
DISPLAY 0.489362 (-440 5135);
PAINT MONO (-440 5135);
FORCEPROP 0 LASTPIN (-450 5075) $PN BG23
J 0
(-440 5085);
DISPLAY 0.489362 (-440 5085);
PAINT MONO (-440 5085);
FORCEPROP 0 LASTPIN (-450 5025) $PN BG25
J 0
(-440 5035);
DISPLAY 0.489362 (-440 5035);
PAINT MONO (-440 5035);
FORCEPROP 0 LASTPIN (-450 4975) $PN BG27
J 0
(-440 4985);
DISPLAY 0.489362 (-440 4985);
PAINT MONO (-440 4985);
FORCEPROP 0 LASTPIN (-450 4925) $PN BG49
J 0
(-440 4935);
DISPLAY 0.489362 (-440 4935);
PAINT MONO (-440 4935);
FORCEPROP 0 LASTPIN (-450 4875) $PN BG51
J 0
(-440 4885);
DISPLAY 0.489362 (-440 4885);
PAINT MONO (-440 4885);
FORCEPROP 0 LASTPIN (-450 4825) $PN BG53
J 0
(-440 4835);
DISPLAY 0.489362 (-440 4835);
PAINT MONO (-440 4835);
FORCEPROP 0 LASTPIN (-450 4775) $PN BG56
J 0
(-440 4785);
DISPLAY 0.489362 (-440 4785);
PAINT MONO (-440 4785);
FORCEPROP 0 LASTPIN (-450 4725) $PN BG58
J 0
(-440 4735);
DISPLAY 0.489362 (-440 4735);
PAINT MONO (-440 4735);
FORCEPROP 0 LASTPIN (-450 4675) $PN BG61
J 0
(-440 4685);
DISPLAY 0.489362 (-440 4685);
PAINT MONO (-440 4685);
FORCEPROP 0 LASTPIN (-450 4625) $PN BG63
J 0
(-440 4635);
DISPLAY 0.489362 (-440 4635);
PAINT MONO (-440 4635);
FORCEPROP 0 LASTPIN (-450 4575) $PN BG65
J 0
(-440 4585);
DISPLAY 0.489362 (-440 4585);
PAINT MONO (-440 4585);
FORCEPROP 0 LASTPIN (-450 4525) $PN BG68
J 0
(-440 4535);
DISPLAY 0.489362 (-440 4535);
PAINT MONO (-440 4535);
FORCEPROP 0 LASTPIN (-450 4475) $PN BG70
J 0
(-440 4485);
DISPLAY 0.489362 (-440 4485);
PAINT MONO (-440 4485);
FORCEPROP 0 LASTPIN (-450 4425) $PN BG72
J 0
(-440 4435);
DISPLAY 0.489362 (-440 4435);
PAINT MONO (-440 4435);
FORCEPROP 0 LASTPIN (-450 4375) $PN BG75
J 0
(-440 4385);
DISPLAY 0.489362 (-440 4385);
PAINT MONO (-440 4385);
FORCEPROP 0 LASTPIN (-450 4325) $PN BH3
J 0
(-440 4335);
DISPLAY 0.489362 (-440 4335);
PAINT MONO (-440 4335);
FORCEPROP 0 LASTPIN (-450 4275) $PN BH5
J 0
(-440 4285);
DISPLAY 0.489362 (-440 4285);
PAINT MONO (-440 4285);
FORCEPROP 0 LASTPIN (-450 4225) $PN BH8
J 0
(-440 4235);
DISPLAY 0.489362 (-440 4235);
PAINT MONO (-440 4235);
FORCEPROP 0 LASTPIN (-450 4175) $PN BH10
J 0
(-440 4185);
DISPLAY 0.489362 (-440 4185);
PAINT MONO (-440 4185);
FORCEPROP 0 LASTPIN (-450 4125) $PN BH12
J 0
(-440 4135);
DISPLAY 0.489362 (-440 4135);
PAINT MONO (-440 4135);
FORCEPROP 0 LASTPIN (-450 4075) $PN BH15
J 0
(-440 4085);
DISPLAY 0.489362 (-440 4085);
PAINT MONO (-440 4085);
FORCEPROP 0 LASTPIN (-450 4025) $PN BH17
J 0
(-440 4035);
DISPLAY 0.489362 (-440 4035);
PAINT MONO (-440 4035);
FORCEPROP 0 LASTPIN (-450 3975) $PN BH19
J 0
(-440 3985);
DISPLAY 0.489362 (-440 3985);
PAINT MONO (-440 3985);
FORCEPROP 0 LASTPIN (-450 3925) $PN BH22
J 0
(-440 3935);
DISPLAY 0.489362 (-440 3935);
PAINT MONO (-440 3935);
FORCEPROP 0 LASTPIN (-450 3875) $PN BH24
J 0
(-440 3885);
DISPLAY 0.489362 (-440 3885);
PAINT MONO (-440 3885);
FORCEPROP 0 LASTPIN (-450 3825) $PN BH26
J 0
(-440 3835);
DISPLAY 0.489362 (-440 3835);
PAINT MONO (-440 3835);
FORCEPROP 0 LASTPIN (-450 3775) $PN BH28
J 0
(-440 3785);
DISPLAY 0.489362 (-440 3785);
PAINT MONO (-440 3785);
FORCEPROP 0 LASTPIN (-450 3725) $PN BH49
J 0
(-440 3735);
DISPLAY 0.489362 (-440 3735);
PAINT MONO (-440 3735);
FORCEPROP 0 LASTPIN (-450 3675) $PN BH50
J 0
(-440 3685);
DISPLAY 0.489362 (-440 3685);
PAINT MONO (-440 3685);
FORCEPROP 0 LASTPIN (-450 3625) $PN BH52
J 0
(-440 3635);
DISPLAY 0.489362 (-440 3635);
PAINT MONO (-440 3635);
FORCEPROP 0 LASTPIN (-450 3575) $PN BH54
J 0
(-440 3585);
DISPLAY 0.489362 (-440 3585);
PAINT MONO (-440 3585);
FORCEPROP 0 LASTPIN (-450 3525) $PN BH57
J 0
(-440 3535);
DISPLAY 0.489362 (-440 3535);
PAINT MONO (-440 3535);
FORCEPROP 0 LASTPIN (-450 3475) $PN BH59
J 0
(-440 3485);
DISPLAY 0.489362 (-440 3485);
PAINT MONO (-440 3485);
FORCEPROP 0 LASTPIN (-450 3425) $PN BH61
J 0
(-440 3435);
DISPLAY 0.489362 (-440 3435);
PAINT MONO (-440 3435);
FORCEPROP 0 LASTPIN (-450 3375) $PN BH64
J 0
(-440 3385);
DISPLAY 0.489362 (-440 3385);
PAINT MONO (-440 3385);
FORCEPROP 0 LASTPIN (-450 3325) $PN BH66
J 0
(-440 3335);
DISPLAY 0.489362 (-440 3335);
PAINT MONO (-440 3335);
FORCEPROP 0 LASTPIN (-450 3275) $PN BH68
J 0
(-440 3285);
DISPLAY 0.489362 (-440 3285);
PAINT MONO (-440 3285);
FORCEPROP 0 LASTPIN (-450 3225) $PN BH71
J 0
(-440 3235);
DISPLAY 0.489362 (-440 3235);
PAINT MONO (-440 3235);
FORCEPROP 0 LASTPIN (-450 3175) $PN BH73
J 0
(-440 3185);
DISPLAY 0.489362 (-440 3185);
PAINT MONO (-440 3185);
FORCEPROP 0 LASTPIN (-450 3125) $PN BJ1
J 0
(-440 3135);
DISPLAY 0.489362 (-440 3135);
PAINT MONO (-440 3135);
FORCEPROP 0 LASTPIN (-450 3075) $PN BJ6
J 0
(-440 3085);
DISPLAY 0.489362 (-440 3085);
PAINT MONO (-440 3085);
FORCEPROP 0 LASTPIN (-450 3025) $PN BJ8
J 0
(-440 3035);
DISPLAY 0.489362 (-440 3035);
PAINT MONO (-440 3035);
FORCEPROP 0 LASTPIN (-450 2975) $PN BJ13
J 0
(-440 2985);
DISPLAY 0.489362 (-440 2985);
PAINT MONO (-440 2985);
FORCEPROP 0 LASTPIN (-450 2925) $PN BJ15
J 0
(-440 2935);
DISPLAY 0.489362 (-440 2935);
PAINT MONO (-440 2935);
FORCEPROP 0 LASTPIN (-450 2875) $PN BJ20
J 0
(-440 2885);
DISPLAY 0.489362 (-440 2885);
PAINT MONO (-440 2885);
FORCEPROP 0 LASTPIN (-450 2825) $PN BJ22
J 0
(-440 2835);
DISPLAY 0.489362 (-440 2835);
PAINT MONO (-440 2835);
FORCEPROP 0 LASTPIN (-450 2775) $PN BJ24
J 0
(-440 2785);
DISPLAY 0.489362 (-440 2785);
PAINT MONO (-440 2785);
FORCEPROP 0 LASTPIN (-450 2725) $PN BJ26
J 0
(-440 2735);
DISPLAY 0.489362 (-440 2735);
PAINT MONO (-440 2735);
FORCEPROP 0 LASTPIN (-450 2675) $PN BJ28
J 0
(-440 2685);
DISPLAY 0.489362 (-440 2685);
PAINT MONO (-440 2685);
FORCEPROP 0 LASTPIN (-450 2625) $PN BJ49
J 0
(-440 2635);
DISPLAY 0.489362 (-440 2635);
PAINT MONO (-440 2635);
FORCEPROP 0 LASTPIN (-450 2575) $PN BJ51
J 0
(-440 2585);
DISPLAY 0.489362 (-440 2585);
PAINT MONO (-440 2585);
FORCEPROP 0 LASTPIN (-450 2525) $PN BJ53
J 0
(-440 2535);
DISPLAY 0.489362 (-440 2535);
PAINT MONO (-440 2535);
FORCEPROP 0 LASTPIN (-450 2475) $PN BJ56
J 0
(-440 2485);
DISPLAY 0.489362 (-440 2485);
PAINT MONO (-440 2485);
FORCEPROP 0 LASTPIN (-450 2425) $PN BJ61
J 0
(-440 2435);
DISPLAY 0.489362 (-440 2435);
PAINT MONO (-440 2435);
FORCEPROP 0 LASTPIN (-450 2375) $PN BJ63
J 0
(-440 2385);
DISPLAY 0.489362 (-440 2385);
PAINT MONO (-440 2385);
FORCEPROP 0 LASTPIN (-450 2325) $PN BJ68
J 0
(-440 2335);
DISPLAY 0.489362 (-440 2335);
PAINT MONO (-440 2335);
FORCEPROP 0 LASTPIN (-450 2275) $PN BJ70
J 0
(-440 2285);
DISPLAY 0.489362 (-440 2285);
PAINT MONO (-440 2285);
FORCEPROP 0 LASTPIN (-450 2225) $PN BJ75
J 0
(-440 2235);
DISPLAY 0.489362 (-440 2235);
PAINT MONO (-440 2235);
FORCEPROP 0 LASTPIN (-450 2175) $PN BK3
J 0
(-440 2185);
DISPLAY 0.489362 (-440 2185);
PAINT MONO (-440 2185);
FORCEPROP 0 LASTPIN (-450 2125) $PN BK5
J 0
(-440 2135);
DISPLAY 0.489362 (-440 2135);
PAINT MONO (-440 2135);
FORCEPROP 0 LASTPIN (-450 2075) $PN BK8
J 0
(-440 2085);
DISPLAY 0.489362 (-440 2085);
PAINT MONO (-440 2085);
FORCEPROP 0 LASTPIN (-450 2025) $PN BK10
J 0
(-440 2035);
DISPLAY 0.489362 (-440 2035);
PAINT MONO (-440 2035);
FORCEPROP 0 LASTPIN (-450 1975) $PN BK12
J 0
(-440 1985);
DISPLAY 0.489362 (-440 1985);
PAINT MONO (-440 1985);
FORCEPROP 0 LASTPIN (-450 1925) $PN BK15
J 0
(-440 1935);
DISPLAY 0.489362 (-440 1935);
PAINT MONO (-440 1935);
FORCEPROP 0 LASTPIN (-450 1875) $PN BK17
J 0
(-440 1885);
DISPLAY 0.489362 (-440 1885);
PAINT MONO (-440 1885);
FORCEPROP 0 LASTPIN (-450 1825) $PN BK19
J 0
(-440 1835);
DISPLAY 0.489362 (-440 1835);
PAINT MONO (-440 1835);
FORCEPROP 0 LASTPIN (-450 1775) $PN BK23
J 0
(-440 1785);
DISPLAY 0.489362 (-440 1785);
PAINT MONO (-440 1785);
FORCEPROP 0 LASTPIN (-450 1725) $PN BK25
J 0
(-440 1735);
DISPLAY 0.489362 (-440 1735);
PAINT MONO (-440 1735);
FORCEPROP 0 LASTPIN (-450 1675) $PN BK27
J 0
(-440 1685);
DISPLAY 0.489362 (-440 1685);
PAINT MONO (-440 1685);
FORCEPROP 0 LASTPIN (-450 1625) $PN BK48
J 0
(-440 1635);
DISPLAY 0.489362 (-440 1635);
PAINT MONO (-440 1635);
FORCEPROP 0 LASTPIN (-450 1575) $PN BK50
J 0
(-440 1585);
DISPLAY 0.489362 (-440 1585);
PAINT MONO (-440 1585);
FORCEPROP 0 LASTPIN (-450 1525) $PN BK52
J 0
(-440 1535);
DISPLAY 0.489362 (-440 1535);
PAINT MONO (-440 1535);
FORCEPROP 0 LASTPIN (-450 1475) $PN BK54
J 0
(-440 1485);
DISPLAY 0.489362 (-440 1485);
PAINT MONO (-440 1485);
FORCEPROP 0 LASTPIN (-450 1425) $PN BK57
J 0
(-440 1435);
DISPLAY 0.489362 (-440 1435);
PAINT MONO (-440 1435);
FORCEPROP 0 LASTPIN (-450 1375) $PN BK59
J 0
(-440 1385);
DISPLAY 0.489362 (-440 1385);
PAINT MONO (-440 1385);
FORCEPROP 0 LASTPIN (-450 1325) $PN BK61
J 0
(-440 1335);
DISPLAY 0.489362 (-440 1335);
PAINT MONO (-440 1335);
FORCEPROP 0 LASTPIN (-450 1275) $PN BK64
J 0
(-440 1285);
DISPLAY 0.489362 (-440 1285);
PAINT MONO (-440 1285);
FORCEPROP 0 LASTPIN (-450 1225) $PN BK66
J 0
(-440 1235);
DISPLAY 0.489362 (-440 1235);
PAINT MONO (-440 1235);
FORCEPROP 0 LASTPIN (-450 1175) $PN BK68
J 0
(-440 1185);
DISPLAY 0.489362 (-440 1185);
PAINT MONO (-440 1185);
FORCEPROP 0 LASTPIN (-450 1125) $PN BK71
J 0
(-440 1135);
DISPLAY 0.489362 (-440 1135);
PAINT MONO (-440 1135);
FORCEPROP 0 LASTPIN (-450 1075) $PN BK73
J 0
(-440 1085);
DISPLAY 0.489362 (-440 1085);
PAINT MONO (-440 1085);
FORCEPROP 0 LASTPIN (-450 1025) $PN BL1
J 0
(-440 1035);
DISPLAY 0.489362 (-440 1035);
PAINT MONO (-440 1035);
FORCEPROP 0 LASTPIN (-450 975) $PN BL4
J 0
(-440 985);
DISPLAY 0.489362 (-440 985);
PAINT MONO (-440 985);
FORCEPROP 0 LASTPIN (-450 925) $PN BL6
J 0
(-440 935);
DISPLAY 0.489362 (-440 935);
PAINT MONO (-440 935);
FORCEPROP 0 LASTPIN (-450 875) $PN BL8
J 0
(-440 885);
DISPLAY 0.489362 (-440 885);
PAINT MONO (-440 885);
FORCEPROP 0 LASTPIN (-450 825) $PN BL11
J 0
(-440 835);
DISPLAY 0.489362 (-440 835);
PAINT MONO (-440 835);
FORCEPROP 0 LASTPIN (-450 775) $PN BL13
J 0
(-440 785);
DISPLAY 0.489362 (-440 785);
PAINT MONO (-440 785);
FORCEPROP 0 LASTPIN (-450 725) $PN BL15
J 0
(-440 735);
DISPLAY 0.489362 (-440 735);
PAINT MONO (-440 735);
FORCEPROP 0 LASTPIN (-450 675) $PN BL18
J 0
(-440 685);
DISPLAY 0.489362 (-440 685);
PAINT MONO (-440 685);
FORCEPROP 0 LASTPIN (-450 625) $PN BL20
J 0
(-440 635);
DISPLAY 0.489362 (-440 635);
PAINT MONO (-440 635);
FORCEPROP 0 LASTPIN (-450 575) $PN BL22
J 0
(-440 585);
DISPLAY 0.489362 (-440 585);
PAINT MONO (-440 585);
FORCEPROP 0 LASTPIN (-450 525) $PN BL24
J 0
(-440 535);
DISPLAY 0.489362 (-440 535);
PAINT MONO (-440 535);
FORCEPROP 2 LAST PART_TYPE SMLF
J 0
(-1400 6700);
DISPLAY 1.021277 (-1400 6700);
FORCEPROP 1 LAST MATERIAL IO
J 0
(-1395 6557);
DISPLAY 0.489362 (-1395 6557);
PAINT SKYBLUE (-1395 6557);
FORCEPROP 2 LAST VALUE SOCKET6096_13568-001
J 0
(-1275 6550);
DISPLAY 0.489362 (-1275 6550);
PAINT SKYBLUE (-1275 6550);
FORCEPROP 1 LAST PART_NUMBER DGA^6000030
J 0
(-1395 6650);
DISPLAY 0.489362 (-1395 6650);
PAINT SKYBLUE (-1395 6650);
FORCEPROP 1 LAST NEEDS_NO_SIZE TRUE
J 0
(-1000 3475);
DISPLAY 0.723404 (-1000 3475);
PAINT GREEN (-1000 3475);
DISPLAY INVISIBLE (-1000 3475);
FORCEPROP 1 LAST CDS_LMAN_SYM_OUTLINE -400,3050,400,-3050
J 0
(-1000 3475);
DISPLAY 0.468085 (-1000 3475);
PAINT GREEN (-1000 3475);
DISPLAY INVISIBLE (-1000 3475);
FORCEPROP 2 LAST CDS_LIB pure_quanta
J 0
(-1000 3475);
DISPLAY INVISIBLE (-1000 3475);
FORCEPROP 1 LAST PATH I24
J 0
(-1000 3475);
DISPLAY 0.723404 (-1000 3475);
PAINT GREEN (-1000 3475);
DISPLAY INVISIBLE (-1000 3475);
FORCEADD UNIVERSAL_GND..1
(-9275 350);
FORCEPROP 3 LASTPIN (-9275 400) SIG_NAME GND\g
J 0
(-9265 410);
DISPLAY 0.659574 (-9265 410);
PAINT MONO (-9265 410);
DISPLAY INVISIBLE (-9265 410);
FORCEPROP 2 LAST CDS_LIB pure_quanta_power
J 0
(-9275 350);
DISPLAY INVISIBLE (-9275 350);
FORCEPROP 1 LAST PATH I39
J 0
(-9200 350);
DISPLAY 0.872340 (-9200 350);
PAINT AQUA (-9200 350);
DISPLAY INVISIBLE (-9200 350);
FORCEPROP 1 LAST HDL_POWER GND
J 1
(-9250 275);
DISPLAY 0.872340 (-9250 275);
PAINT GREEN (-9250 275);
DISPLAY INVISIBLE (-9250 275);
FORCEADD UNIVERSAL_GND..1
(-7750 375);
FORCEPROP 3 LASTPIN (-7750 425) SIG_NAME GND\g
J 0
(-7740 435);
DISPLAY 0.659574 (-7740 435);
PAINT MONO (-7740 435);
DISPLAY INVISIBLE (-7740 435);
FORCEPROP 2 LAST CDS_LIB pure_quanta_power
J 0
(-7750 375);
DISPLAY INVISIBLE (-7750 375);
FORCEPROP 1 LAST PATH I40
J 0
(-7675 375);
DISPLAY 0.872340 (-7675 375);
PAINT AQUA (-7675 375);
DISPLAY INVISIBLE (-7675 375);
FORCEPROP 1 LAST HDL_POWER GND
J 1
(-7725 300);
DISPLAY 0.872340 (-7725 300);
PAINT GREEN (-7725 300);
DISPLAY INVISIBLE (-7725 300);
FORCEADD UNIVERSAL_GND..1
(-6275 400);
FORCEPROP 3 LASTPIN (-6275 450) SIG_NAME GND\g
J 0
(-6265 460);
DISPLAY 0.659574 (-6265 460);
PAINT MONO (-6265 460);
DISPLAY INVISIBLE (-6265 460);
FORCEPROP 2 LAST CDS_LIB pure_quanta_power
J 0
(-6275 400);
DISPLAY INVISIBLE (-6275 400);
FORCEPROP 1 LAST PATH I41
J 0
(-6200 400);
DISPLAY 0.872340 (-6200 400);
PAINT AQUA (-6200 400);
DISPLAY INVISIBLE (-6200 400);
FORCEPROP 1 LAST HDL_POWER GND
J 1
(-6250 325);
DISPLAY 0.872340 (-6250 325);
PAINT GREEN (-6250 325);
DISPLAY INVISIBLE (-6250 325);
FORCEADD UNIVERSAL_GND..1
(-3275 425);
FORCEPROP 3 LASTPIN (-3275 475) SIG_NAME GND\g
J 0
(-3265 485);
DISPLAY 0.659574 (-3265 485);
PAINT MONO (-3265 485);
DISPLAY INVISIBLE (-3265 485);
FORCEPROP 2 LAST CDS_LIB pure_quanta_power
J 0
(-3275 425);
DISPLAY INVISIBLE (-3275 425);
FORCEPROP 1 LAST PATH I43
J 0
(-3200 425);
DISPLAY 0.872340 (-3200 425);
PAINT AQUA (-3200 425);
DISPLAY INVISIBLE (-3200 425);
FORCEPROP 1 LAST HDL_POWER GND
J 1
(-3250 350);
DISPLAY 0.872340 (-3250 350);
PAINT GREEN (-3250 350);
DISPLAY INVISIBLE (-3250 350);
FORCEADD UNIVERSAL_GND..1
(-1650 450);
FORCEPROP 3 LASTPIN (-1650 500) SIG_NAME GND\g
J 0
(-1640 510);
DISPLAY 0.659574 (-1640 510);
PAINT MONO (-1640 510);
DISPLAY INVISIBLE (-1640 510);
FORCEPROP 2 LAST CDS_LIB pure_quanta_power
J 0
(-1650 450);
DISPLAY INVISIBLE (-1650 450);
FORCEPROP 1 LAST PATH I44
J 0
(-1575 450);
DISPLAY 0.872340 (-1575 450);
PAINT AQUA (-1575 450);
DISPLAY INVISIBLE (-1575 450);
FORCEPROP 1 LAST HDL_POWER GND
J 1
(-1625 375);
DISPLAY 0.872340 (-1625 375);
PAINT GREEN (-1625 375);
DISPLAY INVISIBLE (-1625 375);
FORCEADD UNIVERSAL_GND..1
(-7925 375);
FORCEPROP 3 LASTPIN (-7925 425) SIG_NAME GND\g
J 0
(-7915 435);
DISPLAY 0.659574 (-7915 435);
PAINT MONO (-7915 435);
DISPLAY INVISIBLE (-7915 435);
FORCEPROP 2 LAST CDS_LIB pure_quanta_power
J 0
(-7925 375);
DISPLAY INVISIBLE (-7925 375);
FORCEPROP 1 LAST PATH I45
J 0
(-7850 375);
DISPLAY 0.872340 (-7850 375);
PAINT AQUA (-7850 375);
DISPLAY INVISIBLE (-7850 375);
FORCEPROP 1 LAST HDL_POWER GND
J 1
(-7900 300);
DISPLAY 0.872340 (-7900 300);
PAINT GREEN (-7900 300);
DISPLAY INVISIBLE (-7900 300);
FORCEADD UNIVERSAL_GND..1
(-6400 400);
FORCEPROP 3 LASTPIN (-6400 450) SIG_NAME GND\g
J 0
(-6390 460);
DISPLAY 0.659574 (-6390 460);
PAINT MONO (-6390 460);
DISPLAY INVISIBLE (-6390 460);
FORCEPROP 2 LAST CDS_LIB pure_quanta_power
J 0
(-6400 400);
DISPLAY INVISIBLE (-6400 400);
FORCEPROP 1 LAST PATH I46
J 0
(-6325 400);
DISPLAY 0.872340 (-6325 400);
PAINT AQUA (-6325 400);
DISPLAY INVISIBLE (-6325 400);
FORCEPROP 1 LAST HDL_POWER GND
J 1
(-6375 325);
DISPLAY 0.872340 (-6375 325);
PAINT GREEN (-6375 325);
DISPLAY INVISIBLE (-6375 325);
FORCEADD UNIVERSAL_GND..1
(-4925 475);
FORCEPROP 3 LASTPIN (-4925 525) SIG_NAME GND\g
J 0
(-4915 535);
DISPLAY 0.659574 (-4915 535);
PAINT MONO (-4915 535);
DISPLAY INVISIBLE (-4915 535);
FORCEPROP 2 LAST CDS_LIB pure_quanta_power
J 0
(-4925 475);
DISPLAY INVISIBLE (-4925 475);
FORCEPROP 1 LAST PATH I47
J 0
(-4850 475);
DISPLAY 0.872340 (-4850 475);
PAINT AQUA (-4850 475);
DISPLAY INVISIBLE (-4850 475);
FORCEPROP 1 LAST HDL_POWER GND
J 1
(-4900 400);
DISPLAY 0.872340 (-4900 400);
PAINT GREEN (-4900 400);
DISPLAY INVISIBLE (-4900 400);
FORCEADD UNIVERSAL_GND..1
(-3425 500);
FORCEPROP 3 LASTPIN (-3425 550) SIG_NAME GND\g
J 0
(-3415 560);
DISPLAY 0.659574 (-3415 560);
PAINT MONO (-3415 560);
DISPLAY INVISIBLE (-3415 560);
FORCEPROP 2 LAST CDS_LIB pure_quanta_power
J 0
(-3425 500);
DISPLAY INVISIBLE (-3425 500);
FORCEPROP 1 LAST PATH I48
J 0
(-3350 500);
DISPLAY 0.872340 (-3350 500);
PAINT AQUA (-3350 500);
DISPLAY INVISIBLE (-3350 500);
FORCEPROP 1 LAST HDL_POWER GND
J 1
(-3400 425);
DISPLAY 0.872340 (-3400 425);
PAINT GREEN (-3400 425);
DISPLAY INVISIBLE (-3400 425);
FORCEADD UNIVERSAL_GND..1
(-1950 450);
FORCEPROP 3 LASTPIN (-1950 500) SIG_NAME GND\g
J 0
(-1940 510);
DISPLAY 0.659574 (-1940 510);
PAINT MONO (-1940 510);
DISPLAY INVISIBLE (-1940 510);
FORCEPROP 2 LAST CDS_LIB pure_quanta_power
J 0
(-1950 450);
DISPLAY INVISIBLE (-1950 450);
FORCEPROP 1 LAST PATH I49
J 0
(-1875 450);
DISPLAY 0.872340 (-1875 450);
PAINT AQUA (-1875 450);
DISPLAY INVISIBLE (-1875 450);
FORCEPROP 1 LAST HDL_POWER GND
J 1
(-1925 375);
DISPLAY 0.872340 (-1925 375);
PAINT GREEN (-1925 375);
DISPLAY INVISIBLE (-1925 375);
FORCEADD UNIVERSAL_GND..1
(-325 450);
FORCEPROP 3 LASTPIN (-325 500) SIG_NAME GND\g
J 0
(-315 510);
DISPLAY 0.659574 (-315 510);
PAINT MONO (-315 510);
DISPLAY INVISIBLE (-315 510);
FORCEPROP 2 LAST CDS_LIB pure_quanta_power
J 0
(-325 450);
DISPLAY INVISIBLE (-325 450);
FORCEPROP 1 LAST PATH I50
J 0
(-250 450);
DISPLAY 0.872340 (-250 450);
PAINT AQUA (-250 450);
DISPLAY INVISIBLE (-250 450);
FORCEPROP 1 LAST HDL_POWER GND
J 1
(-300 375);
DISPLAY 0.872340 (-300 375);
PAINT GREEN (-300 375);
DISPLAY INVISIBLE (-300 375);
FORCEADD UNIVERSAL_GND..1
(-4775 475);
FORCEPROP 3 LASTPIN (-4775 525) SIG_NAME GND\g
J 0
(-4765 535);
DISPLAY 0.659574 (-4765 535);
PAINT MONO (-4765 535);
DISPLAY INVISIBLE (-4765 535);
FORCEPROP 2 LAST CDS_LIB pure_quanta_power
J 0
(-4775 475);
DISPLAY INVISIBLE (-4775 475);
FORCEPROP 1 LAST PATH I51
J 0
(-4700 475);
DISPLAY 0.872340 (-4700 475);
PAINT AQUA (-4700 475);
DISPLAY INVISIBLE (-4700 475);
FORCEPROP 1 LAST HDL_POWER GND
J 1
(-4750 400);
DISPLAY 0.872340 (-4750 400);
PAINT GREEN (-4750 400);
DISPLAY INVISIBLE (-4750 400);
FORCEADD QUANTA_TITLE_BLOCK_C..1
(-100 100);
FORCEPROP 0 LAST CDS_CON_LAST_MODIFIED Fri Mar 11 14:52:26 2022
J 0
(-1985 115);
DISPLAY INVISIBLE (-1985 115);
FORCEPROP 1 LAST CUSTOM_TXT_CDS <CON_LAST_MODIFIED>
J 0
(-1985 115);
DISPLAY 0.978723 (-1985 115);
FORCEPROP 2 LAST CUSTOM_TXT_CDS <XR_PAGE_TITLE>
J 0
(-7990 5350);
DISPLAY 0.638298 (-7990 5350);
PAINT PINK (-7990 5350);
DISPLAY INVISIBLE (-7990 5350);
FORCEPROP 1 LAST CUSTOM_TXT_CDS <NAME_2>
J 0
(-3275 150);
FORCEPROP 1 LAST CUSTOM_TXT_CDS <NAME_1>
J 0
(-3275 275);
FORCEPROP 1 LAST CUSTOM_TXT_CDS <Q_NUMBER>
J 0
(-1503 203);
DISPLAY 1.212766 (-1503 203);
FORCEPROP 1 LAST CUSTOM_TXT_CDS <Q_PROJ>
J 0
(-2482 202);
DISPLAY 1.212766 (-2482 202);
FORCEPROP 1 LAST CUSTOM_TXT_CDS <Q_REV>
J 0
(-284 203);
DISPLAY 1.212766 (-284 203);
FORCEPROP 1 LAST CUSTOM_TXT_CDS <CON_PAGE_NUM> OF <CON_TOTAL_PAGES>
J 0
(-546 118);
DISPLAY 0.978723 (-546 118);
FORCEPROP 1 LAST Q_DEPT BU9
J 1
(-3863 149);
DISPLAY 1.957447 (-3863 149);
PAINT GREEN (-3863 149);
FORCEPROP 1 LAST Q_TITLE CPU0 VSS 1/3
J 0
(-9400 150);
DISPLAY 2.446809 (-9400 150);
PAINT GREEN (-9400 150);
FORCEPROP 2 LAST PAGE_BORDER TRUE
J 0
(-7990 5350);
DISPLAY 0.638298 (-7990 5350);
PAINT PINK (-7990 5350);
DISPLAY INVISIBLE (-7990 5350);
FORCEPROP 2 LAST CDS_LIB pure_quanta
J 0
(-100 100);
DISPLAY INVISIBLE (-100 100);
FORCEPROP 1 LAST CDS_LMAN_SYM_OUTLINE -9475,6775,100,-125
J 0
(-100 100);
DISPLAY 0.468085 (-100 100);
PAINT GREEN (-100 100);
DISPLAY INVISIBLE (-100 100);
FORCEPROP 1 LAST COMMENT_BODY TRUE
J 0
(-88 87);
DISPLAY 0.978723 (-88 87);
PAINT GREEN (-88 87);
DISPLAY INVISIBLE (-88 87);
FORCEPROP 2 LAST CDS_XR_PAGE_TITLE CR-31 : @T6G_MB_LIB.T6G(SCH_1):PAGE31
J 0
(-7990 5350);
DISPLAY 0.638298 (-7990 5350);
PAINT PINK (-7990 5350);
DISPLAY INVISIBLE (-7990 5350);
WIRE 16 -1 (-9275 450)(-9150 450);
WIRE 16 -1 (-9275 450)(-9275 400);
WIRE 16 -1 (-9275 500)(-9275 450);
WIRE 16 -1 (-9275 500)(-9150 500);
WIRE 16 -1 (-9275 550)(-9275 500);
WIRE 16 -1 (-9150 550)(-9275 550);
WIRE 16 -1 (-9275 600)(-9275 550);
WIRE 16 -1 (-9150 600)(-9275 600);
WIRE 16 -1 (-9275 650)(-9275 600);
WIRE 16 -1 (-9150 650)(-9275 650);
WIRE 16 -1 (-9275 700)(-9275 650);
WIRE 16 -1 (-9150 700)(-9275 700);
WIRE 16 -1 (-9275 750)(-9275 700);
WIRE 16 -1 (-9150 750)(-9275 750);
WIRE 16 -1 (-9275 800)(-9275 750);
WIRE 16 -1 (-9150 800)(-9275 800);
WIRE 16 -1 (-9275 850)(-9275 800);
WIRE 16 -1 (-9150 850)(-9275 850);
WIRE 16 -1 (-9275 900)(-9275 850);
WIRE 16 -1 (-9150 900)(-9275 900);
WIRE 16 -1 (-9275 950)(-9275 900);
WIRE 16 -1 (-9275 950)(-9150 950);
WIRE 16 -1 (-9275 1000)(-9275 950);
WIRE 16 -1 (-9275 1000)(-9150 1000);
WIRE 16 -1 (-9275 1050)(-9275 1000);
WIRE 16 -1 (-9275 1050)(-9150 1050);
WIRE 16 -1 (-9275 1100)(-9275 1050);
WIRE 16 -1 (-9275 1100)(-9150 1100);
WIRE 16 -1 (-9275 1150)(-9275 1100);
WIRE 16 -1 (-9275 1150)(-9150 1150);
WIRE 16 -1 (-9275 1200)(-9275 1150);
WIRE 16 -1 (-9275 1200)(-9150 1200);
WIRE 16 -1 (-9275 1250)(-9275 1200);
WIRE 16 -1 (-9150 1250)(-9275 1250);
WIRE 16 -1 (-9275 1300)(-9275 1250);
WIRE 16 -1 (-9150 1300)(-9275 1300);
WIRE 16 -1 (-9275 1350)(-9275 1300);
WIRE 16 -1 (-9275 1350)(-9150 1350);
WIRE 16 -1 (-9275 1400)(-9275 1350);
WIRE 16 -1 (-9275 1400)(-9150 1400);
WIRE 16 -1 (-9275 1450)(-9275 1400);
WIRE 16 -1 (-9275 1450)(-9150 1450);
WIRE 16 -1 (-9275 1500)(-9275 1450);
WIRE 16 -1 (-9275 1500)(-9150 1500);
WIRE 16 -1 (-9275 1550)(-9275 1500);
WIRE 16 -1 (-9275 1550)(-9150 1550);
WIRE 16 -1 (-9275 1600)(-9275 1550);
WIRE 16 -1 (-9275 1600)(-9150 1600);
WIRE 16 -1 (-9275 1650)(-9275 1600);
WIRE 16 -1 (-9150 1650)(-9275 1650);
WIRE 16 -1 (-9275 1700)(-9275 1650);
WIRE 16 -1 (-9150 1700)(-9275 1700);
WIRE 16 -1 (-9275 1750)(-9275 1700);
WIRE 16 -1 (-9275 1750)(-9150 1750);
WIRE 16 -1 (-9275 1800)(-9275 1750);
WIRE 16 -1 (-9275 1800)(-9150 1800);
WIRE 16 -1 (-9275 1850)(-9275 1800);
WIRE 16 -1 (-9275 1850)(-9150 1850);
WIRE 16 -1 (-9275 1900)(-9275 1850);
WIRE 16 -1 (-9275 1900)(-9150 1900);
WIRE 16 -1 (-9275 1950)(-9275 1900);
WIRE 16 -1 (-9275 1950)(-9150 1950);
WIRE 16 -1 (-9275 2000)(-9275 1950);
WIRE 16 -1 (-9275 2050)(-9275 2000);
WIRE 16 -1 (-9275 2000)(-9150 2000);
WIRE 16 -1 (-9150 2050)(-9275 2050);
WIRE 16 -1 (-9275 2100)(-9275 2050);
WIRE 16 -1 (-9150 2100)(-9275 2100);
WIRE 16 -1 (-9275 2150)(-9275 2100);
WIRE 16 -1 (-9275 2150)(-9150 2150);
WIRE 16 -1 (-9275 2200)(-9275 2150);
WIRE 16 -1 (-9275 2200)(-9150 2200);
WIRE 16 -1 (-9275 2250)(-9275 2200);
WIRE 16 -1 (-9275 2250)(-9150 2250);
WIRE 16 -1 (-9275 2300)(-9275 2250);
WIRE 16 -1 (-9275 2300)(-9150 2300);
WIRE 16 -1 (-9275 2350)(-9275 2300);
WIRE 16 -1 (-9275 2350)(-9150 2350);
WIRE 16 -1 (-9275 2400)(-9275 2350);
WIRE 16 -1 (-9275 2400)(-9150 2400);
WIRE 16 -1 (-9275 2450)(-9275 2400);
WIRE 16 -1 (-9150 2450)(-9275 2450);
WIRE 16 -1 (-9275 2500)(-9275 2450);
WIRE 16 -1 (-9150 2500)(-9275 2500);
WIRE 16 -1 (-9275 2550)(-9275 2500);
WIRE 16 -1 (-9275 2550)(-9150 2550);
WIRE 16 -1 (-9275 2600)(-9275 2550);
WIRE 16 -1 (-9275 2600)(-9150 2600);
WIRE 16 -1 (-9275 2650)(-9275 2600);
WIRE 16 -1 (-9275 2650)(-9150 2650);
WIRE 16 -1 (-9275 2700)(-9275 2650);
WIRE 16 -1 (-9275 2700)(-9150 2700);
WIRE 16 -1 (-9275 2750)(-9275 2700);
WIRE 16 -1 (-9275 2750)(-9150 2750);
WIRE 16 -1 (-9275 2800)(-9275 2750);
WIRE 16 -1 (-9275 2800)(-9150 2800);
WIRE 16 -1 (-9275 2850)(-9275 2800);
WIRE 16 -1 (-9150 2850)(-9275 2850);
WIRE 16 -1 (-9275 2900)(-9275 2850);
WIRE 16 -1 (-9150 2900)(-9275 2900);
WIRE 16 -1 (-9275 2950)(-9275 2900);
WIRE 16 -1 (-9275 2950)(-9150 2950);
WIRE 16 -1 (-9275 3000)(-9275 2950);
WIRE 16 -1 (-9275 3000)(-9150 3000);
WIRE 16 -1 (-9275 3050)(-9275 3000);
WIRE 16 -1 (-9275 3050)(-9150 3050);
WIRE 16 -1 (-9275 3100)(-9275 3050);
WIRE 16 -1 (-9275 3100)(-9150 3100);
WIRE 16 -1 (-9275 3150)(-9275 3100);
WIRE 16 -1 (-9275 3150)(-9150 3150);
WIRE 16 -1 (-9275 3200)(-9275 3150);
WIRE 16 -1 (-9275 3200)(-9150 3200);
WIRE 16 -1 (-9275 3250)(-9275 3200);
WIRE 16 -1 (-9150 3250)(-9275 3250);
WIRE 16 -1 (-9275 3300)(-9275 3250);
WIRE 16 -1 (-9150 3300)(-9275 3300);
WIRE 16 -1 (-9275 3350)(-9275 3300);
WIRE 16 -1 (-9275 3350)(-9150 3350);
WIRE 16 -1 (-9275 3400)(-9275 3350);
WIRE 16 -1 (-9275 3400)(-9150 3400);
WIRE 16 -1 (-9275 3450)(-9275 3400);
WIRE 16 -1 (-9275 3450)(-9150 3450);
WIRE 16 -1 (-9275 3500)(-9275 3450);
WIRE 16 -1 (-9275 3500)(-9150 3500);
WIRE 16 -1 (-9275 3550)(-9275 3500);
WIRE 16 -1 (-9275 3550)(-9150 3550);
WIRE 16 -1 (-9275 3600)(-9275 3550);
WIRE 16 -1 (-9275 3600)(-9150 3600);
WIRE 16 -1 (-9275 3650)(-9275 3600);
WIRE 16 -1 (-9150 3650)(-9275 3650);
WIRE 16 -1 (-9275 3700)(-9275 3650);
WIRE 16 -1 (-9150 3700)(-9275 3700);
WIRE 16 -1 (-9275 3750)(-9275 3700);
WIRE 16 -1 (-9275 3750)(-9150 3750);
WIRE 16 -1 (-9275 3800)(-9275 3750);
WIRE 16 -1 (-9275 3800)(-9150 3800);
WIRE 16 -1 (-9275 3850)(-9275 3800);
WIRE 16 -1 (-9275 3850)(-9150 3850);
WIRE 16 -1 (-9275 3900)(-9275 3850);
WIRE 16 -1 (-9275 3900)(-9150 3900);
WIRE 16 -1 (-9275 3950)(-9275 3900);
WIRE 16 -1 (-9275 3950)(-9150 3950);
WIRE 16 -1 (-9275 4000)(-9275 3950);
WIRE 16 -1 (-9275 4000)(-9150 4000);
WIRE 16 -1 (-9275 4050)(-9275 4000);
WIRE 16 -1 (-9275 4100)(-9275 4050);
WIRE 16 -1 (-9150 4050)(-9275 4050);
WIRE 16 -1 (-9150 4100)(-9275 4100);
WIRE 16 -1 (-9275 4150)(-9275 4100);
WIRE 16 -1 (-9275 4150)(-9150 4150);
WIRE 16 -1 (-9275 4200)(-9275 4150);
WIRE 16 -1 (-9275 4200)(-9150 4200);
WIRE 16 -1 (-9275 4250)(-9275 4200);
WIRE 16 -1 (-9275 4250)(-9150 4250);
WIRE 16 -1 (-9275 4300)(-9275 4250);
WIRE 16 -1 (-9275 4300)(-9150 4300);
WIRE 16 -1 (-9275 4350)(-9275 4300);
WIRE 16 -1 (-9275 4350)(-9150 4350);
WIRE 16 -1 (-9275 4400)(-9275 4350);
WIRE 16 -1 (-9275 4400)(-9150 4400);
WIRE 16 -1 (-9275 4450)(-9275 4400);
WIRE 16 -1 (-9150 4450)(-9275 4450);
WIRE 16 -1 (-9275 4500)(-9275 4450);
WIRE 16 -1 (-9150 4500)(-9275 4500);
WIRE 16 -1 (-9275 4550)(-9275 4500);
WIRE 16 -1 (-9275 4550)(-9150 4550);
WIRE 16 -1 (-9275 4600)(-9275 4550);
WIRE 16 -1 (-9275 4600)(-9150 4600);
WIRE 16 -1 (-9275 4650)(-9275 4600);
WIRE 16 -1 (-9275 4650)(-9150 4650);
WIRE 16 -1 (-9275 4700)(-9275 4650);
WIRE 16 -1 (-9275 4700)(-9150 4700);
WIRE 16 -1 (-9275 4750)(-9275 4700);
WIRE 16 -1 (-9275 4750)(-9150 4750);
WIRE 16 -1 (-9275 4800)(-9275 4750);
WIRE 16 -1 (-9275 4800)(-9150 4800);
WIRE 16 -1 (-9275 4850)(-9275 4800);
WIRE 16 -1 (-9150 4850)(-9275 4850);
WIRE 16 -1 (-9275 4900)(-9275 4850);
WIRE 16 -1 (-9150 4900)(-9275 4900);
WIRE 16 -1 (-9275 4950)(-9275 4900);
WIRE 16 -1 (-9275 4950)(-9150 4950);
WIRE 16 -1 (-9275 5000)(-9275 4950);
WIRE 16 -1 (-9275 5000)(-9150 5000);
WIRE 16 -1 (-9275 5050)(-9275 5000);
WIRE 16 -1 (-9275 5050)(-9150 5050);
WIRE 16 -1 (-9275 5100)(-9275 5050);
WIRE 16 -1 (-9275 5100)(-9150 5100);
WIRE 16 -1 (-9275 5150)(-9275 5100);
WIRE 16 -1 (-9275 5150)(-9150 5150);
WIRE 16 -1 (-9275 5200)(-9275 5150);
WIRE 16 -1 (-9275 5200)(-9150 5200);
WIRE 16 -1 (-9275 5250)(-9275 5200);
WIRE 16 -1 (-9150 5250)(-9275 5250);
WIRE 16 -1 (-9275 5300)(-9275 5250);
WIRE 16 -1 (-9150 5300)(-9275 5300);
WIRE 16 -1 (-9275 5350)(-9275 5300);
WIRE 16 -1 (-9275 5350)(-9150 5350);
WIRE 16 -1 (-9275 5400)(-9275 5350);
WIRE 16 -1 (-9275 5400)(-9150 5400);
WIRE 16 -1 (-9275 5450)(-9275 5400);
WIRE 16 -1 (-9275 5450)(-9150 5450);
WIRE 16 -1 (-9275 5500)(-9275 5450);
WIRE 16 -1 (-9275 5500)(-9150 5500);
WIRE 16 -1 (-9275 5550)(-9275 5500);
WIRE 16 -1 (-9275 5550)(-9150 5550);
WIRE 16 -1 (-9275 5600)(-9275 5550);
WIRE 16 -1 (-9275 5600)(-9150 5600);
WIRE 16 -1 (-9275 5650)(-9275 5600);
WIRE 16 -1 (-9150 5650)(-9275 5650);
WIRE 16 -1 (-9275 5700)(-9275 5650);
WIRE 16 -1 (-9150 5700)(-9275 5700);
WIRE 16 -1 (-9275 5750)(-9275 5700);
WIRE 16 -1 (-9275 5750)(-9150 5750);
WIRE 16 -1 (-9275 5800)(-9275 5750);
WIRE 16 -1 (-9275 5800)(-9150 5800);
WIRE 16 -1 (-9275 5850)(-9275 5800);
WIRE 16 -1 (-9275 5850)(-9150 5850);
WIRE 16 -1 (-9275 5900)(-9275 5850);
WIRE 16 -1 (-9275 5900)(-9150 5900);
WIRE 16 -1 (-9275 5950)(-9275 5900);
WIRE 16 -1 (-9275 5950)(-9150 5950);
WIRE 16 -1 (-9275 6000)(-9275 5950);
WIRE 16 -1 (-9275 6000)(-9150 6000);
WIRE 16 -1 (-9275 6050)(-9275 6000);
WIRE 16 -1 (-9150 6050)(-9275 6050);
WIRE 16 -1 (-9275 6100)(-9275 6050);
WIRE 16 -1 (-9275 6150)(-9275 6100);
WIRE 16 -1 (-9150 6100)(-9275 6100);
WIRE 16 -1 (-9275 6150)(-9150 6150);
WIRE 16 -1 (-9275 6200)(-9275 6150);
WIRE 16 -1 (-9275 6200)(-9150 6200);
WIRE 16 -1 (-9275 6250)(-9275 6200);
WIRE 16 -1 (-9275 6250)(-9150 6250);
WIRE 16 -1 (-9275 6300)(-9275 6250);
WIRE 16 -1 (-9275 6300)(-9150 6300);
WIRE 16 -1 (-9275 6350)(-9275 6300);
WIRE 16 -1 (-9275 6350)(-9150 6350);
WIRE 16 -1 (-7925 450)(-7925 425);
WIRE 16 -1 (-7925 500)(-7925 450);
WIRE 16 -1 (-7925 450)(-8050 450);
WIRE 16 -1 (-7925 550)(-7925 500);
WIRE 16 -1 (-7925 500)(-8050 500);
WIRE 16 -1 (-7925 600)(-7925 550);
WIRE 16 -1 (-7925 550)(-8050 550);
WIRE 16 -1 (-7925 650)(-7925 600);
WIRE 16 -1 (-7925 600)(-8050 600);
WIRE 16 -1 (-7925 700)(-7925 650);
WIRE 16 -1 (-7925 650)(-8050 650);
WIRE 16 -1 (-8050 700)(-7925 700);
WIRE 16 -1 (-7925 750)(-7925 700);
WIRE 16 -1 (-8050 750)(-7925 750);
WIRE 16 -1 (-7925 800)(-7925 750);
WIRE 16 -1 (-7925 850)(-7925 800);
WIRE 16 -1 (-7925 800)(-8050 800);
WIRE 16 -1 (-7925 900)(-7925 850);
WIRE 16 -1 (-7925 850)(-8050 850);
WIRE 16 -1 (-7925 950)(-7925 900);
WIRE 16 -1 (-7925 900)(-8050 900);
WIRE 16 -1 (-7925 1000)(-7925 950);
WIRE 16 -1 (-7925 950)(-8050 950);
WIRE 16 -1 (-7925 1050)(-7925 1000);
WIRE 16 -1 (-7925 1000)(-8050 1000);
WIRE 16 -1 (-7925 1100)(-7925 1050);
WIRE 16 -1 (-7925 1050)(-8050 1050);
WIRE 16 -1 (-8050 1100)(-7925 1100);
WIRE 16 -1 (-7925 1150)(-7925 1100);
WIRE 16 -1 (-8050 1150)(-7925 1150);
WIRE 16 -1 (-7925 1200)(-7925 1150);
WIRE 16 -1 (-7925 1250)(-7925 1200);
WIRE 16 -1 (-7925 1200)(-8050 1200);
WIRE 16 -1 (-7925 1300)(-7925 1250);
WIRE 16 -1 (-7925 1250)(-8050 1250);
WIRE 16 -1 (-7925 1350)(-7925 1300);
WIRE 16 -1 (-7925 1300)(-8050 1300);
WIRE 16 -1 (-7925 1400)(-7925 1350);
WIRE 16 -1 (-7925 1350)(-8050 1350);
WIRE 16 -1 (-7925 1450)(-7925 1400);
WIRE 16 -1 (-7925 1400)(-8050 1400);
WIRE 16 -1 (-7925 1500)(-7925 1450);
WIRE 16 -1 (-7925 1450)(-8050 1450);
WIRE 16 -1 (-8050 1500)(-7925 1500);
WIRE 16 -1 (-7925 1550)(-7925 1500);
WIRE 16 -1 (-7925 1600)(-7925 1550);
WIRE 16 -1 (-8050 1550)(-7925 1550);
WIRE 16 -1 (-7925 1650)(-7925 1600);
WIRE 16 -1 (-7925 1600)(-8050 1600);
WIRE 16 -1 (-7925 1700)(-7925 1650);
WIRE 16 -1 (-7925 1650)(-8050 1650);
WIRE 16 -1 (-7925 1750)(-7925 1700);
WIRE 16 -1 (-7925 1700)(-8050 1700);
WIRE 16 -1 (-7925 1800)(-7925 1750);
WIRE 16 -1 (-7925 1750)(-8050 1750);
WIRE 16 -1 (-7925 1850)(-7925 1800);
WIRE 16 -1 (-7925 1800)(-8050 1800);
WIRE 16 -1 (-7925 1900)(-7925 1850);
WIRE 16 -1 (-7925 1850)(-8050 1850);
WIRE 16 -1 (-8050 1900)(-7925 1900);
WIRE 16 -1 (-7925 1950)(-7925 1900);
WIRE 16 -1 (-8050 1950)(-7925 1950);
WIRE 16 -1 (-7925 2000)(-7925 1950);
WIRE 16 -1 (-7925 2050)(-7925 2000);
WIRE 16 -1 (-7925 2000)(-8050 2000);
WIRE 16 -1 (-7925 2100)(-7925 2050);
WIRE 16 -1 (-7925 2050)(-8050 2050);
WIRE 16 -1 (-7925 2150)(-7925 2100);
WIRE 16 -1 (-7925 2100)(-8050 2100);
WIRE 16 -1 (-7925 2200)(-7925 2150);
WIRE 16 -1 (-7925 2150)(-8050 2150);
WIRE 16 -1 (-7925 2250)(-7925 2200);
WIRE 16 -1 (-7925 2200)(-8050 2200);
WIRE 16 -1 (-7925 2300)(-7925 2250);
WIRE 16 -1 (-7925 2250)(-8050 2250);
WIRE 16 -1 (-8050 2300)(-7925 2300);
WIRE 16 -1 (-7925 2350)(-7925 2300);
WIRE 16 -1 (-8050 2350)(-7925 2350);
WIRE 16 -1 (-7925 2400)(-7925 2350);
WIRE 16 -1 (-7925 2450)(-7925 2400);
WIRE 16 -1 (-7925 2400)(-8050 2400);
WIRE 16 -1 (-7925 2500)(-7925 2450);
WIRE 16 -1 (-7925 2450)(-8050 2450);
WIRE 16 -1 (-7925 2550)(-7925 2500);
WIRE 16 -1 (-7925 2500)(-8050 2500);
WIRE 16 -1 (-7925 2600)(-7925 2550);
WIRE 16 -1 (-7925 2550)(-8050 2550);
WIRE 16 -1 (-7925 2650)(-7925 2600);
WIRE 16 -1 (-7925 2600)(-8050 2600);
WIRE 16 -1 (-7925 2700)(-7925 2650);
WIRE 16 -1 (-7925 2650)(-8050 2650);
WIRE 16 -1 (-8050 2700)(-7925 2700);
WIRE 16 -1 (-7925 2750)(-7925 2700);
WIRE 16 -1 (-8050 2750)(-7925 2750);
WIRE 16 -1 (-7925 2800)(-7925 2750);
WIRE 16 -1 (-7925 2850)(-7925 2800);
WIRE 16 -1 (-7925 2800)(-8050 2800);
WIRE 16 -1 (-7925 2900)(-7925 2850);
WIRE 16 -1 (-7925 2850)(-8050 2850);
WIRE 16 -1 (-7925 2950)(-7925 2900);
WIRE 16 -1 (-7925 2900)(-8050 2900);
WIRE 16 -1 (-7925 3000)(-7925 2950);
WIRE 16 -1 (-7925 2950)(-8050 2950);
WIRE 16 -1 (-7925 3050)(-7925 3000);
WIRE 16 -1 (-7925 3000)(-8050 3000);
WIRE 16 -1 (-7925 3100)(-7925 3050);
WIRE 16 -1 (-7925 3050)(-8050 3050);
WIRE 16 -1 (-7925 3150)(-7925 3100);
WIRE 16 -1 (-8050 3100)(-7925 3100);
WIRE 16 -1 (-8050 3150)(-7925 3150);
WIRE 16 -1 (-7925 3200)(-7925 3150);
WIRE 16 -1 (-7925 3250)(-7925 3200);
WIRE 16 -1 (-7925 3200)(-8050 3200);
WIRE 16 -1 (-7925 3300)(-7925 3250);
WIRE 16 -1 (-7925 3250)(-8050 3250);
WIRE 16 -1 (-7925 3350)(-7925 3300);
WIRE 16 -1 (-7925 3300)(-8050 3300);
WIRE 16 -1 (-7925 3400)(-7925 3350);
WIRE 16 -1 (-7925 3350)(-8050 3350);
WIRE 16 -1 (-7925 3450)(-7925 3400);
WIRE 16 -1 (-7925 3400)(-8050 3400);
WIRE 16 -1 (-7925 3500)(-7925 3450);
WIRE 16 -1 (-7925 3450)(-8050 3450);
WIRE 16 -1 (-8050 3500)(-7925 3500);
WIRE 16 -1 (-7925 3550)(-7925 3500);
WIRE 16 -1 (-8050 3550)(-7925 3550);
WIRE 16 -1 (-7925 3600)(-7925 3550);
WIRE 16 -1 (-7925 3650)(-7925 3600);
WIRE 16 -1 (-7925 3600)(-8050 3600);
WIRE 16 -1 (-7925 3700)(-7925 3650);
WIRE 16 -1 (-7925 3650)(-8050 3650);
WIRE 16 -1 (-7925 3750)(-7925 3700);
WIRE 16 -1 (-7925 3700)(-8050 3700);
WIRE 16 -1 (-7925 3800)(-7925 3750);
WIRE 16 -1 (-7925 3750)(-8050 3750);
WIRE 16 -1 (-7925 3850)(-7925 3800);
WIRE 16 -1 (-7925 3800)(-8050 3800);
WIRE 16 -1 (-7925 3900)(-7925 3850);
WIRE 16 -1 (-7925 3850)(-8050 3850);
WIRE 16 -1 (-8050 3900)(-7925 3900);
WIRE 16 -1 (-7925 3950)(-7925 3900);
WIRE 16 -1 (-8050 3950)(-7925 3950);
WIRE 16 -1 (-7925 4000)(-7925 3950);
WIRE 16 -1 (-7925 4050)(-7925 4000);
WIRE 16 -1 (-7925 4000)(-8050 4000);
WIRE 16 -1 (-7925 4100)(-7925 4050);
WIRE 16 -1 (-7925 4050)(-8050 4050);
WIRE 16 -1 (-7925 4150)(-7925 4100);
WIRE 16 -1 (-7925 4100)(-8050 4100);
WIRE 16 -1 (-7925 4200)(-7925 4150);
WIRE 16 -1 (-7925 4150)(-8050 4150);
WIRE 16 -1 (-7925 4250)(-7925 4200);
WIRE 16 -1 (-7925 4200)(-8050 4200);
WIRE 16 -1 (-7925 4300)(-7925 4250);
WIRE 16 -1 (-7925 4250)(-8050 4250);
WIRE 16 -1 (-8050 4300)(-7925 4300);
WIRE 16 -1 (-7925 4350)(-7925 4300);
WIRE 16 -1 (-8050 4350)(-7925 4350);
WIRE 16 -1 (-7925 4400)(-7925 4350);
WIRE 16 -1 (-7925 4450)(-7925 4400);
WIRE 16 -1 (-7925 4400)(-8050 4400);
WIRE 16 -1 (-7925 4500)(-7925 4450);
WIRE 16 -1 (-7925 4450)(-8050 4450);
WIRE 16 -1 (-7925 4550)(-7925 4500);
WIRE 16 -1 (-7925 4500)(-8050 4500);
WIRE 16 -1 (-7925 4600)(-7925 4550);
WIRE 16 -1 (-7925 4550)(-8050 4550);
WIRE 16 -1 (-7925 4650)(-7925 4600);
WIRE 16 -1 (-7925 4600)(-8050 4600);
WIRE 16 -1 (-7925 4700)(-7925 4650);
WIRE 16 -1 (-7925 4650)(-8050 4650);
WIRE 16 -1 (-8050 4700)(-7925 4700);
WIRE 16 -1 (-7925 4750)(-7925 4700);
WIRE 16 -1 (-8050 4750)(-7925 4750);
WIRE 16 -1 (-7925 4800)(-7925 4750);
WIRE 16 -1 (-7925 4850)(-7925 4800);
WIRE 16 -1 (-7925 4800)(-8050 4800);
WIRE 16 -1 (-7925 4900)(-7925 4850);
WIRE 16 -1 (-7925 4850)(-8050 4850);
WIRE 16 -1 (-7925 4950)(-7925 4900);
WIRE 16 -1 (-7925 4900)(-8050 4900);
WIRE 16 -1 (-7925 5000)(-7925 4950);
WIRE 16 -1 (-7925 4950)(-8050 4950);
WIRE 16 -1 (-7925 5050)(-7925 5000);
WIRE 16 -1 (-7925 5000)(-8050 5000);
WIRE 16 -1 (-7925 5100)(-7925 5050);
WIRE 16 -1 (-7925 5050)(-8050 5050);
WIRE 16 -1 (-8050 5100)(-7925 5100);
WIRE 16 -1 (-7925 5150)(-7925 5100);
WIRE 16 -1 (-7925 5200)(-7925 5150);
WIRE 16 -1 (-8050 5150)(-7925 5150);
WIRE 16 -1 (-7925 5250)(-7925 5200);
WIRE 16 -1 (-7925 5200)(-8050 5200);
WIRE 16 -1 (-7925 5300)(-7925 5250);
WIRE 16 -1 (-7925 5250)(-8050 5250);
WIRE 16 -1 (-7925 5350)(-7925 5300);
WIRE 16 -1 (-7925 5300)(-8050 5300);
WIRE 16 -1 (-7925 5400)(-7925 5350);
WIRE 16 -1 (-7925 5350)(-8050 5350);
WIRE 16 -1 (-7925 5450)(-7925 5400);
WIRE 16 -1 (-7925 5400)(-8050 5400);
WIRE 16 -1 (-7925 5500)(-7925 5450);
WIRE 16 -1 (-7925 5450)(-8050 5450);
WIRE 16 -1 (-8050 5500)(-7925 5500);
WIRE 16 -1 (-7925 5550)(-7925 5500);
WIRE 16 -1 (-8050 5550)(-7925 5550);
WIRE 16 -1 (-7925 5600)(-7925 5550);
WIRE 16 -1 (-7925 5650)(-7925 5600);
WIRE 16 -1 (-7925 5600)(-8050 5600);
WIRE 16 -1 (-7925 5700)(-7925 5650);
WIRE 16 -1 (-7925 5650)(-8050 5650);
WIRE 16 -1 (-7925 5750)(-7925 5700);
WIRE 16 -1 (-7925 5700)(-8050 5700);
WIRE 16 -1 (-7925 5800)(-7925 5750);
WIRE 16 -1 (-7925 5750)(-8050 5750);
WIRE 16 -1 (-7925 5850)(-7925 5800);
WIRE 16 -1 (-7925 5800)(-8050 5800);
WIRE 16 -1 (-7925 5900)(-7925 5850);
WIRE 16 -1 (-7925 5850)(-8050 5850);
WIRE 16 -1 (-8050 5900)(-7925 5900);
WIRE 16 -1 (-7925 5950)(-7925 5900);
WIRE 16 -1 (-8050 5950)(-7925 5950);
WIRE 16 -1 (-7925 6000)(-7925 5950);
WIRE 16 -1 (-8050 6000)(-7925 6000);
WIRE 16 -1 (-7925 6050)(-7925 6000);
WIRE 16 -1 (-8050 6050)(-7925 6050);
WIRE 16 -1 (-7925 6100)(-7925 6050);
WIRE 16 -1 (-8050 6100)(-7925 6100);
WIRE 16 -1 (-7925 6150)(-7925 6100);
WIRE 16 -1 (-7925 6200)(-7925 6150);
WIRE 16 -1 (-8050 6150)(-7925 6150);
WIRE 16 -1 (-8050 6200)(-7925 6200);
WIRE 16 -1 (-7925 6250)(-7925 6200);
WIRE 16 -1 (-8050 6250)(-7925 6250);
WIRE 16 -1 (-7925 6300)(-7925 6250);
WIRE 16 -1 (-7925 6350)(-7925 6300);
WIRE 16 -1 (-7925 6300)(-8050 6300);
WIRE 16 -1 (-7925 6350)(-8050 6350);
WIRE 16 -1 (-7625 475)(-7750 475);
WIRE 16 -1 (-7750 525)(-7750 475);
WIRE 16 -1 (-7750 475)(-7750 425);
WIRE 16 -1 (-7625 525)(-7750 525);
WIRE 16 -1 (-7750 575)(-7750 525);
WIRE 16 -1 (-7625 575)(-7750 575);
WIRE 16 -1 (-7750 625)(-7750 575);
WIRE 16 -1 (-7625 625)(-7750 625);
WIRE 16 -1 (-7750 675)(-7750 625);
WIRE 16 -1 (-7625 675)(-7750 675);
WIRE 16 -1 (-7750 725)(-7750 675);
WIRE 16 -1 (-7625 725)(-7750 725);
WIRE 16 -1 (-7750 775)(-7750 725);
WIRE 16 -1 (-7625 775)(-7750 775);
WIRE 16 -1 (-7750 825)(-7750 775);
WIRE 16 -1 (-7625 825)(-7750 825);
WIRE 16 -1 (-7750 875)(-7750 825);
WIRE 16 -1 (-7750 875)(-7625 875);
WIRE 16 -1 (-7750 925)(-7750 875);
WIRE 16 -1 (-7750 925)(-7625 925);
WIRE 16 -1 (-7750 975)(-7750 925);
WIRE 16 -1 (-7750 1025)(-7750 975);
WIRE 16 -1 (-7750 975)(-7625 975);
WIRE 16 -1 (-7750 1025)(-7625 1025);
WIRE 16 -1 (-7750 1075)(-7750 1025);
WIRE 16 -1 (-7750 1075)(-7625 1075);
WIRE 16 -1 (-7750 1125)(-7750 1075);
WIRE 16 -1 (-7750 1125)(-7625 1125);
WIRE 16 -1 (-7750 1175)(-7750 1125);
WIRE 16 -1 (-7625 1175)(-7750 1175);
WIRE 16 -1 (-7750 1225)(-7750 1175);
WIRE 16 -1 (-7625 1225)(-7750 1225);
WIRE 16 -1 (-7750 1275)(-7750 1225);
WIRE 16 -1 (-7750 1275)(-7625 1275);
WIRE 16 -1 (-7750 1325)(-7750 1275);
WIRE 16 -1 (-7750 1325)(-7625 1325);
WIRE 16 -1 (-7750 1375)(-7750 1325);
WIRE 16 -1 (-7750 1375)(-7625 1375);
WIRE 16 -1 (-7750 1425)(-7750 1375);
WIRE 16 -1 (-7750 1425)(-7625 1425);
WIRE 16 -1 (-7750 1475)(-7750 1425);
WIRE 16 -1 (-7750 1475)(-7625 1475);
WIRE 16 -1 (-7750 1525)(-7750 1475);
WIRE 16 -1 (-7750 1525)(-7625 1525);
WIRE 16 -1 (-7750 1575)(-7750 1525);
WIRE 16 -1 (-7625 1575)(-7750 1575);
WIRE 16 -1 (-7750 1625)(-7750 1575);
WIRE 16 -1 (-7625 1625)(-7750 1625);
WIRE 16 -1 (-7750 1675)(-7750 1625);
WIRE 16 -1 (-7750 1675)(-7625 1675);
WIRE 16 -1 (-7750 1725)(-7750 1675);
WIRE 16 -1 (-7750 1725)(-7625 1725);
WIRE 16 -1 (-7750 1775)(-7750 1725);
WIRE 16 -1 (-7750 1775)(-7625 1775);
WIRE 16 -1 (-7750 1825)(-7750 1775);
WIRE 16 -1 (-7750 1825)(-7625 1825);
WIRE 16 -1 (-7750 1875)(-7750 1825);
WIRE 16 -1 (-7750 1875)(-7625 1875);
WIRE 16 -1 (-7750 1925)(-7750 1875);
WIRE 16 -1 (-7750 1925)(-7625 1925);
WIRE 16 -1 (-7750 1975)(-7750 1925);
WIRE 16 -1 (-7625 1975)(-7750 1975);
WIRE 16 -1 (-7750 2025)(-7750 1975);
WIRE 16 -1 (-7750 2075)(-7750 2025);
WIRE 16 -1 (-7625 2025)(-7750 2025);
WIRE 16 -1 (-7750 2075)(-7625 2075);
WIRE 16 -1 (-7750 2125)(-7750 2075);
WIRE 16 -1 (-7750 2125)(-7625 2125);
WIRE 16 -1 (-7750 2175)(-7750 2125);
WIRE 16 -1 (-7750 2175)(-7625 2175);
WIRE 16 -1 (-7750 2225)(-7750 2175);
WIRE 16 -1 (-7750 2225)(-7625 2225);
WIRE 16 -1 (-7750 2275)(-7750 2225);
WIRE 16 -1 (-7750 2275)(-7625 2275);
WIRE 16 -1 (-7750 2325)(-7750 2275);
WIRE 16 -1 (-7750 2325)(-7625 2325);
WIRE 16 -1 (-7750 2375)(-7750 2325);
WIRE 16 -1 (-7625 2375)(-7750 2375);
WIRE 16 -1 (-7750 2425)(-7750 2375);
WIRE 16 -1 (-7625 2425)(-7750 2425);
WIRE 16 -1 (-7750 2475)(-7750 2425);
WIRE 16 -1 (-7750 2475)(-7625 2475);
WIRE 16 -1 (-7750 2525)(-7750 2475);
WIRE 16 -1 (-7750 2525)(-7625 2525);
WIRE 16 -1 (-7750 2575)(-7750 2525);
WIRE 16 -1 (-7750 2575)(-7625 2575);
WIRE 16 -1 (-7750 2625)(-7750 2575);
WIRE 16 -1 (-7750 2625)(-7625 2625);
WIRE 16 -1 (-7750 2675)(-7750 2625);
WIRE 16 -1 (-7750 2675)(-7625 2675);
WIRE 16 -1 (-7750 2725)(-7750 2675);
WIRE 16 -1 (-7750 2725)(-7625 2725);
WIRE 16 -1 (-7750 2775)(-7750 2725);
WIRE 16 -1 (-7625 2775)(-7750 2775);
WIRE 16 -1 (-7750 2825)(-7750 2775);
WIRE 16 -1 (-7625 2825)(-7750 2825);
WIRE 16 -1 (-7750 2875)(-7750 2825);
WIRE 16 -1 (-7750 2875)(-7625 2875);
WIRE 16 -1 (-7750 2925)(-7750 2875);
WIRE 16 -1 (-7750 2925)(-7625 2925);
WIRE 16 -1 (-7750 2975)(-7750 2925);
WIRE 16 -1 (-7750 2975)(-7625 2975);
WIRE 16 -1 (-7750 3025)(-7750 2975);
WIRE 16 -1 (-7750 3075)(-7750 3025);
WIRE 16 -1 (-7750 3025)(-7625 3025);
WIRE 16 -1 (-7750 3075)(-7625 3075);
WIRE 16 -1 (-7750 3125)(-7750 3075);
WIRE 16 -1 (-7750 3125)(-7625 3125);
WIRE 16 -1 (-7750 3175)(-7750 3125);
WIRE 16 -1 (-7625 3175)(-7750 3175);
WIRE 16 -1 (-7750 3225)(-7750 3175);
WIRE 16 -1 (-7625 3225)(-7750 3225);
WIRE 16 -1 (-7750 3275)(-7750 3225);
WIRE 16 -1 (-7750 3275)(-7625 3275);
WIRE 16 -1 (-7750 3325)(-7750 3275);
WIRE 16 -1 (-7750 3325)(-7625 3325);
WIRE 16 -1 (-7750 3375)(-7750 3325);
WIRE 16 -1 (-7750 3375)(-7625 3375);
WIRE 16 -1 (-7750 3425)(-7750 3375);
WIRE 16 -1 (-7750 3425)(-7625 3425);
WIRE 16 -1 (-7750 3475)(-7750 3425);
WIRE 16 -1 (-7750 3475)(-7625 3475);
WIRE 16 -1 (-7750 3525)(-7750 3475);
WIRE 16 -1 (-7750 3525)(-7625 3525);
WIRE 16 -1 (-7750 3575)(-7750 3525);
WIRE 16 -1 (-7625 3575)(-7750 3575);
WIRE 16 -1 (-7750 3625)(-7750 3575);
WIRE 16 -1 (-7625 3625)(-7750 3625);
WIRE 16 -1 (-7750 3675)(-7750 3625);
WIRE 16 -1 (-7750 3675)(-7625 3675);
WIRE 16 -1 (-7750 3725)(-7750 3675);
WIRE 16 -1 (-7750 3725)(-7625 3725);
WIRE 16 -1 (-7750 3775)(-7750 3725);
WIRE 16 -1 (-7750 3775)(-7625 3775);
WIRE 16 -1 (-7750 3825)(-7750 3775);
WIRE 16 -1 (-7750 3825)(-7625 3825);
WIRE 16 -1 (-7750 3875)(-7750 3825);
WIRE 16 -1 (-7750 3875)(-7625 3875);
WIRE 16 -1 (-7750 3925)(-7750 3875);
WIRE 16 -1 (-7750 3925)(-7625 3925);
WIRE 16 -1 (-7750 3975)(-7750 3925);
WIRE 16 -1 (-7625 3975)(-7750 3975);
WIRE 16 -1 (-7750 4025)(-7750 3975);
WIRE 16 -1 (-7625 4025)(-7750 4025);
WIRE 16 -1 (-7750 4075)(-7750 4025);
WIRE 16 -1 (-7750 4125)(-7750 4075);
WIRE 16 -1 (-7750 4075)(-7625 4075);
WIRE 16 -1 (-7750 4125)(-7625 4125);
WIRE 16 -1 (-7750 4175)(-7750 4125);
WIRE 16 -1 (-7750 4175)(-7625 4175);
WIRE 16 -1 (-7750 4225)(-7750 4175);
WIRE 16 -1 (-7750 4225)(-7625 4225);
WIRE 16 -1 (-7750 4275)(-7750 4225);
WIRE 16 -1 (-7750 4275)(-7625 4275);
WIRE 16 -1 (-7750 4325)(-7750 4275);
WIRE 16 -1 (-7750 4325)(-7625 4325);
WIRE 16 -1 (-7750 4375)(-7750 4325);
WIRE 16 -1 (-7625 4375)(-7750 4375);
WIRE 16 -1 (-7750 4425)(-7750 4375);
WIRE 16 -1 (-7625 4425)(-7750 4425);
WIRE 16 -1 (-7750 4475)(-7750 4425);
WIRE 16 -1 (-7750 4475)(-7625 4475);
WIRE 16 -1 (-7750 4525)(-7750 4475);
WIRE 16 -1 (-7750 4525)(-7625 4525);
WIRE 16 -1 (-7750 4575)(-7750 4525);
WIRE 16 -1 (-7750 4575)(-7625 4575);
WIRE 16 -1 (-7750 4625)(-7750 4575);
WIRE 16 -1 (-7750 4625)(-7625 4625);
WIRE 16 -1 (-7750 4675)(-7750 4625);
WIRE 16 -1 (-7750 4675)(-7625 4675);
WIRE 16 -1 (-7750 4725)(-7750 4675);
WIRE 16 -1 (-7750 4725)(-7625 4725);
WIRE 16 -1 (-7750 4775)(-7750 4725);
WIRE 16 -1 (-7625 4775)(-7750 4775);
WIRE 16 -1 (-7750 4825)(-7750 4775);
WIRE 16 -1 (-7625 4825)(-7750 4825);
WIRE 16 -1 (-7750 4875)(-7750 4825);
WIRE 16 -1 (-7750 4875)(-7625 4875);
WIRE 16 -1 (-7750 4925)(-7750 4875);
WIRE 16 -1 (-7750 4925)(-7625 4925);
WIRE 16 -1 (-7750 4975)(-7750 4925);
WIRE 16 -1 (-7750 4975)(-7625 4975);
WIRE 16 -1 (-7750 5025)(-7750 4975);
WIRE 16 -1 (-7750 5025)(-7625 5025);
WIRE 16 -1 (-7750 5075)(-7750 5025);
WIRE 16 -1 (-7750 5125)(-7750 5075);
WIRE 16 -1 (-7750 5075)(-7625 5075);
WIRE 16 -1 (-7750 5125)(-7625 5125);
WIRE 16 -1 (-7750 5175)(-7750 5125);
WIRE 16 -1 (-7625 5175)(-7750 5175);
WIRE 16 -1 (-7750 5225)(-7750 5175);
WIRE 16 -1 (-7625 5225)(-7750 5225);
WIRE 16 -1 (-7750 5275)(-7750 5225);
WIRE 16 -1 (-7750 5275)(-7625 5275);
WIRE 16 -1 (-7750 5325)(-7750 5275);
WIRE 16 -1 (-7750 5325)(-7625 5325);
WIRE 16 -1 (-7750 5375)(-7750 5325);
WIRE 16 -1 (-7750 5375)(-7625 5375);
WIRE 16 -1 (-7750 5425)(-7750 5375);
WIRE 16 -1 (-7750 5425)(-7625 5425);
WIRE 16 -1 (-7750 5475)(-7750 5425);
WIRE 16 -1 (-7750 5475)(-7625 5475);
WIRE 16 -1 (-7750 5525)(-7750 5475);
WIRE 16 -1 (-7750 5525)(-7625 5525);
WIRE 16 -1 (-7750 5575)(-7750 5525);
WIRE 16 -1 (-7625 5575)(-7750 5575);
WIRE 16 -1 (-7750 5625)(-7750 5575);
WIRE 16 -1 (-7625 5625)(-7750 5625);
WIRE 16 -1 (-7750 5675)(-7750 5625);
WIRE 16 -1 (-7750 5675)(-7625 5675);
WIRE 16 -1 (-7750 5725)(-7750 5675);
WIRE 16 -1 (-7750 5725)(-7625 5725);
WIRE 16 -1 (-7750 5775)(-7750 5725);
WIRE 16 -1 (-7750 5775)(-7625 5775);
WIRE 16 -1 (-7750 5825)(-7750 5775);
WIRE 16 -1 (-7750 5825)(-7625 5825);
WIRE 16 -1 (-7750 5875)(-7750 5825);
WIRE 16 -1 (-7750 5875)(-7625 5875);
WIRE 16 -1 (-7750 5925)(-7750 5875);
WIRE 16 -1 (-7750 5925)(-7625 5925);
WIRE 16 -1 (-7750 5975)(-7750 5925);
WIRE 16 -1 (-7625 5975)(-7750 5975);
WIRE 16 -1 (-7750 6025)(-7750 5975);
WIRE 16 -1 (-7625 6025)(-7750 6025);
WIRE 16 -1 (-7750 6075)(-7750 6025);
WIRE 16 -1 (-7750 6075)(-7625 6075);
WIRE 16 -1 (-7750 6125)(-7750 6075);
WIRE 16 -1 (-7750 6175)(-7750 6125);
WIRE 16 -1 (-7750 6125)(-7625 6125);
WIRE 16 -1 (-7750 6175)(-7625 6175);
WIRE 16 -1 (-7750 6225)(-7750 6175);
WIRE 16 -1 (-7750 6225)(-7625 6225);
WIRE 16 -1 (-7750 6275)(-7750 6225);
WIRE 16 -1 (-7750 6275)(-7625 6275);
WIRE 16 -1 (-6400 525)(-6400 475);
WIRE 16 -1 (-6400 525)(-6525 525);
WIRE 16 -1 (-6400 575)(-6400 525);
WIRE 16 -1 (-6400 475)(-6400 450);
WIRE 16 -1 (-6400 475)(-6525 475);
WIRE 16 -1 (-6400 575)(-6525 575);
WIRE 16 -1 (-6400 625)(-6400 575);
WIRE 16 -1 (-6400 625)(-6525 625);
WIRE 16 -1 (-6400 675)(-6400 625);
WIRE 16 -1 (-6400 675)(-6525 675);
WIRE 16 -1 (-6400 725)(-6400 675);
WIRE 16 -1 (-6525 725)(-6400 725);
WIRE 16 -1 (-6400 775)(-6400 725);
WIRE 16 -1 (-6525 775)(-6400 775);
WIRE 16 -1 (-6400 825)(-6400 775);
WIRE 16 -1 (-6400 825)(-6525 825);
WIRE 16 -1 (-6400 875)(-6400 825);
WIRE 16 -1 (-6400 875)(-6525 875);
WIRE 16 -1 (-6400 925)(-6400 875);
WIRE 16 -1 (-6400 925)(-6525 925);
WIRE 16 -1 (-6400 975)(-6400 925);
WIRE 16 -1 (-6400 1025)(-6400 975);
WIRE 16 -1 (-6400 975)(-6525 975);
WIRE 16 -1 (-6400 1025)(-6525 1025);
WIRE 16 -1 (-6400 1075)(-6400 1025);
WIRE 16 -1 (-6400 1075)(-6525 1075);
WIRE 16 -1 (-6400 1125)(-6400 1075);
WIRE 16 -1 (-6525 1125)(-6400 1125);
WIRE 16 -1 (-6400 1175)(-6400 1125);
WIRE 16 -1 (-6525 1175)(-6400 1175);
WIRE 16 -1 (-6400 1225)(-6400 1175);
WIRE 16 -1 (-6400 1225)(-6525 1225);
WIRE 16 -1 (-6400 1275)(-6400 1225);
WIRE 16 -1 (-6400 1275)(-6525 1275);
WIRE 16 -1 (-6400 1325)(-6400 1275);
WIRE 16 -1 (-6400 1325)(-6525 1325);
WIRE 16 -1 (-6400 1375)(-6400 1325);
WIRE 16 -1 (-6400 1375)(-6525 1375);
WIRE 16 -1 (-6400 1425)(-6400 1375);
WIRE 16 -1 (-6400 1425)(-6525 1425);
WIRE 16 -1 (-6400 1475)(-6400 1425);
WIRE 16 -1 (-6400 1475)(-6525 1475);
WIRE 16 -1 (-6400 1525)(-6400 1475);
WIRE 16 -1 (-6400 1575)(-6400 1525);
WIRE 16 -1 (-6525 1525)(-6400 1525);
WIRE 16 -1 (-6525 1575)(-6400 1575);
WIRE 16 -1 (-6400 1625)(-6400 1575);
WIRE 16 -1 (-6400 1625)(-6525 1625);
WIRE 16 -1 (-6400 1675)(-6400 1625);
WIRE 16 -1 (-6400 1675)(-6525 1675);
WIRE 16 -1 (-6400 1725)(-6400 1675);
WIRE 16 -1 (-6400 1725)(-6525 1725);
WIRE 16 -1 (-6400 1775)(-6400 1725);
WIRE 16 -1 (-6400 1775)(-6525 1775);
WIRE 16 -1 (-6400 1825)(-6400 1775);
WIRE 16 -1 (-6400 1825)(-6525 1825);
WIRE 16 -1 (-6400 1875)(-6400 1825);
WIRE 16 -1 (-6400 1875)(-6525 1875);
WIRE 16 -1 (-6400 1925)(-6400 1875);
WIRE 16 -1 (-6525 1925)(-6400 1925);
WIRE 16 -1 (-6400 1975)(-6400 1925);
WIRE 16 -1 (-6525 1975)(-6400 1975);
WIRE 16 -1 (-6400 2025)(-6400 1975);
WIRE 16 -1 (-6400 2075)(-6400 2025);
WIRE 16 -1 (-6400 2025)(-6525 2025);
WIRE 16 -1 (-6400 2075)(-6525 2075);
WIRE 16 -1 (-6400 2125)(-6400 2075);
WIRE 16 -1 (-6400 2125)(-6525 2125);
WIRE 16 -1 (-6400 2175)(-6400 2125);
WIRE 16 -1 (-6400 2175)(-6525 2175);
WIRE 16 -1 (-6400 2225)(-6400 2175);
WIRE 16 -1 (-6400 2225)(-6525 2225);
WIRE 16 -1 (-6400 2275)(-6400 2225);
WIRE 16 -1 (-6400 2275)(-6525 2275);
WIRE 16 -1 (-6400 2325)(-6400 2275);
WIRE 16 -1 (-6525 2325)(-6400 2325);
WIRE 16 -1 (-6400 2375)(-6400 2325);
WIRE 16 -1 (-6525 2375)(-6400 2375);
WIRE 16 -1 (-6400 2425)(-6400 2375);
WIRE 16 -1 (-6400 2425)(-6525 2425);
WIRE 16 -1 (-6400 2475)(-6400 2425);
WIRE 16 -1 (-6400 2475)(-6525 2475);
WIRE 16 -1 (-6400 2525)(-6400 2475);
WIRE 16 -1 (-6400 2575)(-6400 2525);
WIRE 16 -1 (-6400 2525)(-6525 2525);
WIRE 16 -1 (-6400 2575)(-6525 2575);
WIRE 16 -1 (-6400 2625)(-6400 2575);
WIRE 16 -1 (-6400 2625)(-6525 2625);
WIRE 16 -1 (-6400 2675)(-6400 2625);
WIRE 16 -1 (-6400 2675)(-6525 2675);
WIRE 16 -1 (-6400 2725)(-6400 2675);
WIRE 16 -1 (-6525 2725)(-6400 2725);
WIRE 16 -1 (-6400 2775)(-6400 2725);
WIRE 16 -1 (-6525 2775)(-6400 2775);
WIRE 16 -1 (-6400 2825)(-6400 2775);
WIRE 16 -1 (-6400 2825)(-6525 2825);
WIRE 16 -1 (-6400 2875)(-6400 2825);
WIRE 16 -1 (-6400 2875)(-6525 2875);
WIRE 16 -1 (-6400 2925)(-6400 2875);
WIRE 16 -1 (-6400 2925)(-6525 2925);
WIRE 16 -1 (-6400 2975)(-6400 2925);
WIRE 16 -1 (-6400 2975)(-6525 2975);
WIRE 16 -1 (-6400 3025)(-6400 2975);
WIRE 16 -1 (-6400 3075)(-6400 3025);
WIRE 16 -1 (-6400 3025)(-6525 3025);
WIRE 16 -1 (-6400 3075)(-6525 3075);
WIRE 16 -1 (-6400 3125)(-6400 3075);
WIRE 16 -1 (-6525 3125)(-6400 3125);
WIRE 16 -1 (-6400 3175)(-6400 3125);
WIRE 16 -1 (-6525 3175)(-6400 3175);
WIRE 16 -1 (-6400 3225)(-6400 3175);
WIRE 16 -1 (-6400 3225)(-6525 3225);
WIRE 16 -1 (-6400 3275)(-6400 3225);
WIRE 16 -1 (-6400 3275)(-6525 3275);
WIRE 16 -1 (-6400 3325)(-6400 3275);
WIRE 16 -1 (-6400 3325)(-6525 3325);
WIRE 16 -1 (-6400 3375)(-6400 3325);
WIRE 16 -1 (-6400 3375)(-6525 3375);
WIRE 16 -1 (-6400 3425)(-6400 3375);
WIRE 16 -1 (-6400 3425)(-6525 3425);
WIRE 16 -1 (-6400 3475)(-6400 3425);
WIRE 16 -1 (-6400 3475)(-6525 3475);
WIRE 16 -1 (-6400 3525)(-6400 3475);
WIRE 16 -1 (-6525 3525)(-6400 3525);
WIRE 16 -1 (-6400 3575)(-6400 3525);
WIRE 16 -1 (-6400 3625)(-6400 3575);
WIRE 16 -1 (-6525 3575)(-6400 3575);
WIRE 16 -1 (-6400 3625)(-6525 3625);
WIRE 16 -1 (-6400 3675)(-6400 3625);
WIRE 16 -1 (-6400 3675)(-6525 3675);
WIRE 16 -1 (-6400 3725)(-6400 3675);
WIRE 16 -1 (-6400 3725)(-6525 3725);
WIRE 16 -1 (-6400 3775)(-6400 3725);
WIRE 16 -1 (-6400 3775)(-6525 3775);
WIRE 16 -1 (-6400 3825)(-6400 3775);
WIRE 16 -1 (-6400 3825)(-6525 3825);
WIRE 16 -1 (-6400 3875)(-6400 3825);
WIRE 16 -1 (-6400 3875)(-6525 3875);
WIRE 16 -1 (-6400 3925)(-6400 3875);
WIRE 16 -1 (-6525 3925)(-6400 3925);
WIRE 16 -1 (-6400 3975)(-6400 3925);
WIRE 16 -1 (-6525 3975)(-6400 3975);
WIRE 16 -1 (-6400 4025)(-6400 3975);
WIRE 16 -1 (-6400 4025)(-6525 4025);
WIRE 16 -1 (-6400 4075)(-6400 4025);
WIRE 16 -1 (-6400 4125)(-6400 4075);
WIRE 16 -1 (-6400 4075)(-6525 4075);
WIRE 16 -1 (-6400 4125)(-6525 4125);
WIRE 16 -1 (-6400 4175)(-6400 4125);
WIRE 16 -1 (-6400 4175)(-6525 4175);
WIRE 16 -1 (-6400 4225)(-6400 4175);
WIRE 16 -1 (-6400 4225)(-6525 4225);
WIRE 16 -1 (-6400 4275)(-6400 4225);
WIRE 16 -1 (-6400 4275)(-6525 4275);
WIRE 16 -1 (-6400 4325)(-6400 4275);
WIRE 16 -1 (-6525 4325)(-6400 4325);
WIRE 16 -1 (-6400 4375)(-6400 4325);
WIRE 16 -1 (-6525 4375)(-6400 4375);
WIRE 16 -1 (-6400 4425)(-6400 4375);
WIRE 16 -1 (-6400 4425)(-6525 4425);
WIRE 16 -1 (-6400 4475)(-6400 4425);
WIRE 16 -1 (-6400 4475)(-6525 4475);
WIRE 16 -1 (-6400 4525)(-6400 4475);
WIRE 16 -1 (-6400 4525)(-6525 4525);
WIRE 16 -1 (-6400 4575)(-6400 4525);
WIRE 16 -1 (-6400 4625)(-6400 4575);
WIRE 16 -1 (-6400 4575)(-6525 4575);
WIRE 16 -1 (-6400 4625)(-6525 4625);
WIRE 16 -1 (-6400 4675)(-6400 4625);
WIRE 16 -1 (-6400 4675)(-6525 4675);
WIRE 16 -1 (-6400 4725)(-6400 4675);
WIRE 16 -1 (-6525 4725)(-6400 4725);
WIRE 16 -1 (-6400 4775)(-6400 4725);
WIRE 16 -1 (-6525 4775)(-6400 4775);
WIRE 16 -1 (-6400 4825)(-6400 4775);
WIRE 16 -1 (-6400 4825)(-6525 4825);
WIRE 16 -1 (-6400 4875)(-6400 4825);
WIRE 16 -1 (-6400 4875)(-6525 4875);
WIRE 16 -1 (-6400 4925)(-6400 4875);
WIRE 16 -1 (-6400 4925)(-6525 4925);
WIRE 16 -1 (-6400 4975)(-6400 4925);
WIRE 16 -1 (-6400 4975)(-6525 4975);
WIRE 16 -1 (-6400 5025)(-6400 4975);
WIRE 16 -1 (-6400 5025)(-6525 5025);
WIRE 16 -1 (-6400 5075)(-6400 5025);
WIRE 16 -1 (-6400 5125)(-6400 5075);
WIRE 16 -1 (-6400 5075)(-6525 5075);
WIRE 16 -1 (-6525 5125)(-6400 5125);
WIRE 16 -1 (-6400 5175)(-6400 5125);
WIRE 16 -1 (-6525 5175)(-6400 5175);
WIRE 16 -1 (-6400 5225)(-6400 5175);
WIRE 16 -1 (-6400 5225)(-6525 5225);
WIRE 16 -1 (-6400 5275)(-6400 5225);
WIRE 16 -1 (-6400 5275)(-6525 5275);
WIRE 16 -1 (-6400 5325)(-6400 5275);
WIRE 16 -1 (-6400 5325)(-6525 5325);
WIRE 16 -1 (-6400 5375)(-6400 5325);
WIRE 16 -1 (-6400 5375)(-6525 5375);
WIRE 16 -1 (-6400 5425)(-6400 5375);
WIRE 16 -1 (-6400 5425)(-6525 5425);
WIRE 16 -1 (-6400 5475)(-6400 5425);
WIRE 16 -1 (-6400 5475)(-6525 5475);
WIRE 16 -1 (-6400 5525)(-6400 5475);
WIRE 16 -1 (-6525 5525)(-6400 5525);
WIRE 16 -1 (-6400 5575)(-6400 5525);
WIRE 16 -1 (-6525 5575)(-6400 5575);
WIRE 16 -1 (-6400 5625)(-6400 5575);
WIRE 16 -1 (-6400 5675)(-6400 5625);
WIRE 16 -1 (-6400 5625)(-6525 5625);
WIRE 16 -1 (-6400 5675)(-6525 5675);
WIRE 16 -1 (-6400 5725)(-6400 5675);
WIRE 16 -1 (-6400 5725)(-6525 5725);
WIRE 16 -1 (-6400 5775)(-6400 5725);
WIRE 16 -1 (-6400 5775)(-6525 5775);
WIRE 16 -1 (-6400 5825)(-6400 5775);
WIRE 16 -1 (-6400 5825)(-6525 5825);
WIRE 16 -1 (-6400 5875)(-6400 5825);
WIRE 16 -1 (-6400 5875)(-6525 5875);
WIRE 16 -1 (-6400 5925)(-6400 5875);
WIRE 16 -1 (-6525 5925)(-6400 5925);
WIRE 16 -1 (-6400 5975)(-6400 5925);
WIRE 16 -1 (-6525 5975)(-6400 5975);
WIRE 16 -1 (-6400 6025)(-6400 5975);
WIRE 16 -1 (-6525 6025)(-6400 6025);
WIRE 16 -1 (-6400 6075)(-6400 6025);
WIRE 16 -1 (-6525 6075)(-6400 6075);
WIRE 16 -1 (-6400 6125)(-6400 6075);
WIRE 16 -1 (-6400 6175)(-6400 6125);
WIRE 16 -1 (-6525 6125)(-6400 6125);
WIRE 16 -1 (-6525 6175)(-6400 6175);
WIRE 16 -1 (-6400 6225)(-6400 6175);
WIRE 16 -1 (-6525 6225)(-6400 6225);
WIRE 16 -1 (-6400 6275)(-6400 6225);
WIRE 16 -1 (-6525 6275)(-6400 6275);
WIRE 16 -1 (-6275 550)(-6275 500);
WIRE 16 -1 (-6150 550)(-6275 550);
WIRE 16 -1 (-6275 600)(-6275 550);
WIRE 16 -1 (-6150 500)(-6275 500);
WIRE 16 -1 (-6275 500)(-6275 450);
WIRE 16 -1 (-6150 600)(-6275 600);
WIRE 16 -1 (-6275 650)(-6275 600);
WIRE 16 -1 (-6150 650)(-6275 650);
WIRE 16 -1 (-6275 700)(-6275 650);
WIRE 16 -1 (-6150 700)(-6275 700);
WIRE 16 -1 (-6275 750)(-6275 700);
WIRE 16 -1 (-6275 800)(-6275 750);
WIRE 16 -1 (-6150 750)(-6275 750);
WIRE 16 -1 (-6150 800)(-6275 800);
WIRE 16 -1 (-6275 850)(-6275 800);
WIRE 16 -1 (-6150 850)(-6275 850);
WIRE 16 -1 (-6275 900)(-6275 850);
WIRE 16 -1 (-6275 900)(-6150 900);
WIRE 16 -1 (-6275 950)(-6275 900);
WIRE 16 -1 (-6275 950)(-6150 950);
WIRE 16 -1 (-6275 1000)(-6275 950);
WIRE 16 -1 (-6275 1050)(-6275 1000);
WIRE 16 -1 (-6275 1000)(-6150 1000);
WIRE 16 -1 (-6275 1050)(-6150 1050);
WIRE 16 -1 (-6275 1100)(-6275 1050);
WIRE 16 -1 (-6275 1100)(-6150 1100);
WIRE 16 -1 (-6275 1150)(-6275 1100);
WIRE 16 -1 (-6275 1150)(-6150 1150);
WIRE 16 -1 (-6275 1200)(-6275 1150);
WIRE 16 -1 (-6150 1200)(-6275 1200);
WIRE 16 -1 (-6275 1250)(-6275 1200);
WIRE 16 -1 (-6275 1300)(-6275 1250);
WIRE 16 -1 (-6150 1250)(-6275 1250);
WIRE 16 -1 (-6275 1300)(-6150 1300);
WIRE 16 -1 (-6275 1350)(-6275 1300);
WIRE 16 -1 (-6275 1350)(-6150 1350);
WIRE 16 -1 (-6275 1400)(-6275 1350);
WIRE 16 -1 (-6275 1400)(-6150 1400);
WIRE 16 -1 (-6275 1450)(-6275 1400);
WIRE 16 -1 (-6275 1450)(-6150 1450);
WIRE 16 -1 (-6275 1500)(-6275 1450);
WIRE 16 -1 (-6275 1550)(-6275 1500);
WIRE 16 -1 (-6275 1500)(-6150 1500);
WIRE 16 -1 (-6275 1550)(-6150 1550);
WIRE 16 -1 (-6275 1600)(-6275 1550);
WIRE 16 -1 (-6150 1600)(-6275 1600);
WIRE 16 -1 (-6275 1650)(-6275 1600);
WIRE 16 -1 (-6150 1650)(-6275 1650);
WIRE 16 -1 (-6275 1700)(-6275 1650);
WIRE 16 -1 (-6275 1700)(-6150 1700);
WIRE 16 -1 (-6275 1750)(-6275 1700);
WIRE 16 -1 (-6275 1800)(-6275 1750);
WIRE 16 -1 (-6275 1750)(-6150 1750);
WIRE 16 -1 (-6275 1800)(-6150 1800);
WIRE 16 -1 (-6275 1850)(-6275 1800);
WIRE 16 -1 (-6275 1850)(-6150 1850);
WIRE 16 -1 (-6275 1900)(-6275 1850);
WIRE 16 -1 (-6275 1900)(-6150 1900);
WIRE 16 -1 (-6275 1950)(-6275 1900);
WIRE 16 -1 (-6275 1950)(-6150 1950);
WIRE 16 -1 (-6275 2000)(-6275 1950);
WIRE 16 -1 (-6275 2050)(-6275 2000);
WIRE 16 -1 (-6150 2000)(-6275 2000);
WIRE 16 -1 (-6150 2050)(-6275 2050);
WIRE 16 -1 (-6275 2100)(-6275 2050);
WIRE 16 -1 (-6275 2100)(-6150 2100);
WIRE 16 -1 (-6275 2150)(-6275 2100);
WIRE 16 -1 (-6275 2150)(-6150 2150);
WIRE 16 -1 (-6275 2200)(-6275 2150);
WIRE 16 -1 (-6275 2200)(-6150 2200);
WIRE 16 -1 (-6275 2250)(-6275 2200);
WIRE 16 -1 (-6275 2250)(-6150 2250);
WIRE 16 -1 (-6275 2300)(-6275 2250);
WIRE 16 -1 (-6275 2350)(-6275 2300);
WIRE 16 -1 (-6275 2300)(-6150 2300);
WIRE 16 -1 (-6275 2350)(-6150 2350);
WIRE 16 -1 (-6275 2400)(-6275 2350);
WIRE 16 -1 (-6150 2400)(-6275 2400);
WIRE 16 -1 (-6275 2450)(-6275 2400);
WIRE 16 -1 (-6150 2450)(-6275 2450);
WIRE 16 -1 (-6275 2500)(-6275 2450);
WIRE 16 -1 (-6275 2500)(-6150 2500);
WIRE 16 -1 (-6275 2550)(-6275 2500);
WIRE 16 -1 (-6275 2600)(-6275 2550);
WIRE 16 -1 (-6275 2550)(-6150 2550);
WIRE 16 -1 (-6275 2600)(-6150 2600);
WIRE 16 -1 (-6275 2650)(-6275 2600);
WIRE 16 -1 (-6275 2650)(-6150 2650);
WIRE 16 -1 (-6275 2700)(-6275 2650);
WIRE 16 -1 (-6275 2700)(-6150 2700);
WIRE 16 -1 (-6275 2750)(-6275 2700);
WIRE 16 -1 (-6275 2750)(-6150 2750);
WIRE 16 -1 (-6275 2800)(-6275 2750);
WIRE 16 -1 (-6275 2850)(-6275 2800);
WIRE 16 -1 (-6150 2800)(-6275 2800);
WIRE 16 -1 (-6150 2850)(-6275 2850);
WIRE 16 -1 (-6275 2900)(-6275 2850);
WIRE 16 -1 (-6275 2900)(-6150 2900);
WIRE 16 -1 (-6275 2950)(-6275 2900);
WIRE 16 -1 (-6275 2950)(-6150 2950);
WIRE 16 -1 (-6275 3000)(-6275 2950);
WIRE 16 -1 (-6275 3000)(-6150 3000);
WIRE 16 -1 (-6275 3050)(-6275 3000);
WIRE 16 -1 (-6275 3100)(-6275 3050);
WIRE 16 -1 (-6275 3050)(-6150 3050);
WIRE 16 -1 (-6275 3100)(-6150 3100);
WIRE 16 -1 (-6275 3150)(-6275 3100);
WIRE 16 -1 (-6275 3150)(-6150 3150);
WIRE 16 -1 (-6275 3200)(-6275 3150);
WIRE 16 -1 (-6150 3200)(-6275 3200);
WIRE 16 -1 (-6275 3250)(-6275 3200);
WIRE 16 -1 (-6150 3250)(-6275 3250);
WIRE 16 -1 (-6275 3300)(-6275 3250);
WIRE 16 -1 (-6275 3350)(-6275 3300);
WIRE 16 -1 (-6275 3300)(-6150 3300);
WIRE 16 -1 (-6275 3350)(-6150 3350);
WIRE 16 -1 (-6275 3400)(-6275 3350);
WIRE 16 -1 (-6275 3400)(-6150 3400);
WIRE 16 -1 (-6275 3450)(-6275 3400);
WIRE 16 -1 (-6275 3450)(-6150 3450);
WIRE 16 -1 (-6275 3500)(-6275 3450);
WIRE 16 -1 (-6275 3500)(-6150 3500);
WIRE 16 -1 (-6275 3550)(-6275 3500);
WIRE 16 -1 (-6275 3600)(-6275 3550);
WIRE 16 -1 (-6275 3550)(-6150 3550);
WIRE 16 -1 (-6150 3600)(-6275 3600);
WIRE 16 -1 (-6275 3650)(-6275 3600);
WIRE 16 -1 (-6150 3650)(-6275 3650);
WIRE 16 -1 (-6275 3700)(-6275 3650);
WIRE 16 -1 (-6275 3700)(-6150 3700);
WIRE 16 -1 (-6275 3750)(-6275 3700);
WIRE 16 -1 (-6275 3750)(-6150 3750);
WIRE 16 -1 (-6275 3800)(-6275 3750);
WIRE 16 -1 (-6275 3850)(-6275 3800);
WIRE 16 -1 (-6275 3800)(-6150 3800);
WIRE 16 -1 (-6275 3850)(-6150 3850);
WIRE 16 -1 (-6275 3900)(-6275 3850);
WIRE 16 -1 (-6275 3900)(-6150 3900);
WIRE 16 -1 (-6275 3950)(-6275 3900);
WIRE 16 -1 (-6275 3950)(-6150 3950);
WIRE 16 -1 (-6275 4000)(-6275 3950);
WIRE 16 -1 (-6150 4000)(-6275 4000);
WIRE 16 -1 (-6275 4050)(-6275 4000);
WIRE 16 -1 (-6275 4100)(-6275 4050);
WIRE 16 -1 (-6150 4050)(-6275 4050);
WIRE 16 -1 (-6275 4100)(-6150 4100);
WIRE 16 -1 (-6275 4150)(-6275 4100);
WIRE 16 -1 (-6275 4150)(-6150 4150);
WIRE 16 -1 (-6275 4200)(-6275 4150);
WIRE 16 -1 (-6275 4200)(-6150 4200);
WIRE 16 -1 (-6275 4250)(-6275 4200);
WIRE 16 -1 (-6275 4250)(-6150 4250);
WIRE 16 -1 (-6275 4300)(-6275 4250);
WIRE 16 -1 (-6275 4300)(-6150 4300);
WIRE 16 -1 (-6275 4350)(-6275 4300);
WIRE 16 -1 (-6275 4400)(-6275 4350);
WIRE 16 -1 (-6275 4350)(-6150 4350);
WIRE 16 -1 (-6150 4400)(-6275 4400);
WIRE 16 -1 (-6275 4450)(-6275 4400);
WIRE 16 -1 (-6150 4450)(-6275 4450);
WIRE 16 -1 (-6275 4500)(-6275 4450);
WIRE 16 -1 (-6275 4500)(-6150 4500);
WIRE 16 -1 (-6275 4550)(-6275 4500);
WIRE 16 -1 (-6275 4550)(-6150 4550);
WIRE 16 -1 (-6275 4600)(-6275 4550);
WIRE 16 -1 (-6275 4650)(-6275 4600);
WIRE 16 -1 (-6275 4600)(-6150 4600);
WIRE 16 -1 (-6275 4650)(-6150 4650);
WIRE 16 -1 (-6275 4700)(-6275 4650);
WIRE 16 -1 (-6275 4700)(-6150 4700);
WIRE 16 -1 (-6275 4750)(-6275 4700);
WIRE 16 -1 (-6275 4750)(-6150 4750);
WIRE 16 -1 (-6275 4800)(-6275 4750);
WIRE 16 -1 (-6150 4800)(-6275 4800);
WIRE 16 -1 (-6275 4850)(-6275 4800);
WIRE 16 -1 (-6275 4900)(-6275 4850);
WIRE 16 -1 (-6150 4850)(-6275 4850);
WIRE 16 -1 (-6275 4900)(-6150 4900);
WIRE 16 -1 (-6275 4950)(-6275 4900);
WIRE 16 -1 (-6275 4950)(-6150 4950);
WIRE 16 -1 (-6275 5000)(-6275 4950);
WIRE 16 -1 (-6275 5000)(-6150 5000);
WIRE 16 -1 (-6275 5050)(-6275 5000);
WIRE 16 -1 (-6275 5050)(-6150 5050);
WIRE 16 -1 (-6275 5100)(-6275 5050);
WIRE 16 -1 (-6275 5150)(-6275 5100);
WIRE 16 -1 (-6275 5100)(-6150 5100);
WIRE 16 -1 (-6275 5150)(-6150 5150);
WIRE 16 -1 (-6275 5200)(-6275 5150);
WIRE 16 -1 (-6150 5200)(-6275 5200);
WIRE 16 -1 (-6275 5250)(-6275 5200);
WIRE 16 -1 (-6150 5250)(-6275 5250);
WIRE 16 -1 (-6275 5300)(-6275 5250);
WIRE 16 -1 (-6275 5300)(-6150 5300);
WIRE 16 -1 (-6275 5350)(-6275 5300);
WIRE 16 -1 (-6275 5400)(-6275 5350);
WIRE 16 -1 (-6275 5350)(-6150 5350);
WIRE 16 -1 (-6275 5400)(-6150 5400);
WIRE 16 -1 (-6275 5450)(-6275 5400);
WIRE 16 -1 (-6275 5450)(-6150 5450);
WIRE 16 -1 (-6275 5500)(-6275 5450);
WIRE 16 -1 (-6275 5500)(-6150 5500);
WIRE 16 -1 (-6275 5550)(-6275 5500);
WIRE 16 -1 (-6275 5550)(-6150 5550);
WIRE 16 -1 (-6275 5600)(-6275 5550);
WIRE 16 -1 (-6275 5650)(-6275 5600);
WIRE 16 -1 (-6150 5600)(-6275 5600);
WIRE 16 -1 (-6150 5650)(-6275 5650);
WIRE 16 -1 (-6275 5700)(-6275 5650);
WIRE 16 -1 (-6275 5700)(-6150 5700);
WIRE 16 -1 (-6275 5750)(-6275 5700);
WIRE 16 -1 (-6275 5750)(-6150 5750);
WIRE 16 -1 (-6275 5800)(-6275 5750);
WIRE 16 -1 (-6275 5800)(-6150 5800);
WIRE 16 -1 (-6275 5850)(-6275 5800);
WIRE 16 -1 (-6275 5900)(-6275 5850);
WIRE 16 -1 (-6275 5850)(-6150 5850);
WIRE 16 -1 (-6275 5900)(-6150 5900);
WIRE 16 -1 (-6275 5950)(-6275 5900);
WIRE 16 -1 (-6275 5950)(-6150 5950);
WIRE 16 -1 (-6275 6000)(-6275 5950);
WIRE 16 -1 (-6150 6000)(-6275 6000);
WIRE 16 -1 (-6275 6050)(-6275 6000);
WIRE 16 -1 (-6150 6050)(-6275 6050);
WIRE 16 -1 (-6275 6100)(-6275 6050);
WIRE 16 -1 (-6275 6150)(-6275 6100);
WIRE 16 -1 (-6275 6100)(-6150 6100);
WIRE 16 -1 (-6275 6150)(-6150 6150);
WIRE 16 -1 (-6275 6200)(-6275 6150);
WIRE 16 -1 (-6275 6200)(-6150 6200);
WIRE 16 -1 (-6275 6250)(-6275 6200);
WIRE 16 -1 (-6275 6250)(-6150 6250);
WIRE 16 -1 (-6275 6300)(-6275 6250);
WIRE 16 -1 (-6275 6300)(-6150 6300);
WIRE 16 -1 (-4925 600)(-4925 550);
WIRE 16 -1 (-4925 650)(-4925 600);
WIRE 16 -1 (-4925 600)(-5050 600);
WIRE 16 -1 (-4925 550)(-4925 525);
WIRE 16 -1 (-4925 550)(-5050 550);
WIRE 16 -1 (-4925 700)(-4925 650);
WIRE 16 -1 (-4925 650)(-5050 650);
WIRE 16 -1 (-4925 750)(-4925 700);
WIRE 16 -1 (-4925 700)(-5050 700);
WIRE 16 -1 (-4925 800)(-4925 750);
WIRE 16 -1 (-4925 750)(-5050 750);
WIRE 16 -1 (-4925 850)(-4925 800);
WIRE 16 -1 (-5050 800)(-4925 800);
WIRE 16 -1 (-5050 850)(-4925 850);
WIRE 16 -1 (-4925 900)(-4925 850);
WIRE 16 -1 (-4925 950)(-4925 900);
WIRE 16 -1 (-4925 900)(-5050 900);
WIRE 16 -1 (-4925 1000)(-4925 950);
WIRE 16 -1 (-4925 950)(-5050 950);
WIRE 16 -1 (-4925 1050)(-4925 1000);
WIRE 16 -1 (-4925 1000)(-5050 1000);
WIRE 16 -1 (-4925 1100)(-4925 1050);
WIRE 16 -1 (-4925 1050)(-5050 1050);
WIRE 16 -1 (-4925 1150)(-4925 1100);
WIRE 16 -1 (-4925 1100)(-5050 1100);
WIRE 16 -1 (-4925 1200)(-4925 1150);
WIRE 16 -1 (-4925 1150)(-5050 1150);
WIRE 16 -1 (-5050 1200)(-4925 1200);
WIRE 16 -1 (-4925 1250)(-4925 1200);
WIRE 16 -1 (-5050 1250)(-4925 1250);
WIRE 16 -1 (-4925 1300)(-4925 1250);
WIRE 16 -1 (-4925 1350)(-4925 1300);
WIRE 16 -1 (-4925 1300)(-5050 1300);
WIRE 16 -1 (-4925 1400)(-4925 1350);
WIRE 16 -1 (-4925 1350)(-5050 1350);
WIRE 16 -1 (-4925 1450)(-4925 1400);
WIRE 16 -1 (-4925 1400)(-5050 1400);
WIRE 16 -1 (-4925 1500)(-4925 1450);
WIRE 16 -1 (-4925 1450)(-5050 1450);
WIRE 16 -1 (-4925 1550)(-4925 1500);
WIRE 16 -1 (-4925 1500)(-5050 1500);
WIRE 16 -1 (-4925 1600)(-4925 1550);
WIRE 16 -1 (-4925 1550)(-5050 1550);
WIRE 16 -1 (-5050 1600)(-4925 1600);
WIRE 16 -1 (-4925 1650)(-4925 1600);
WIRE 16 -1 (-5050 1650)(-4925 1650);
WIRE 16 -1 (-4925 1700)(-4925 1650);
WIRE 16 -1 (-4925 1750)(-4925 1700);
WIRE 16 -1 (-4925 1700)(-5050 1700);
WIRE 16 -1 (-4925 1800)(-4925 1750);
WIRE 16 -1 (-4925 1750)(-5050 1750);
WIRE 16 -1 (-4925 1850)(-4925 1800);
WIRE 16 -1 (-4925 1800)(-5050 1800);
WIRE 16 -1 (-4925 1900)(-4925 1850);
WIRE 16 -1 (-4925 1850)(-5050 1850);
WIRE 16 -1 (-4925 1950)(-4925 1900);
WIRE 16 -1 (-4925 1900)(-5050 1900);
WIRE 16 -1 (-4925 2000)(-4925 1950);
WIRE 16 -1 (-4925 1950)(-5050 1950);
WIRE 16 -1 (-5050 2000)(-4925 2000);
WIRE 16 -1 (-4925 2050)(-4925 2000);
WIRE 16 -1 (-4925 2100)(-4925 2050);
WIRE 16 -1 (-5050 2050)(-4925 2050);
WIRE 16 -1 (-4925 2150)(-4925 2100);
WIRE 16 -1 (-4925 2100)(-5050 2100);
WIRE 16 -1 (-4925 2200)(-4925 2150);
WIRE 16 -1 (-4925 2150)(-5050 2150);
WIRE 16 -1 (-4925 2250)(-4925 2200);
WIRE 16 -1 (-4925 2200)(-5050 2200);
WIRE 16 -1 (-4925 2300)(-4925 2250);
WIRE 16 -1 (-4925 2250)(-5050 2250);
WIRE 16 -1 (-4925 2350)(-4925 2300);
WIRE 16 -1 (-4925 2300)(-5050 2300);
WIRE 16 -1 (-4925 2400)(-4925 2350);
WIRE 16 -1 (-4925 2350)(-5050 2350);
WIRE 16 -1 (-5050 2400)(-4925 2400);
WIRE 16 -1 (-4925 2450)(-4925 2400);
WIRE 16 -1 (-5050 2450)(-4925 2450);
WIRE 16 -1 (-4925 2500)(-4925 2450);
WIRE 16 -1 (-4925 2550)(-4925 2500);
WIRE 16 -1 (-4925 2500)(-5050 2500);
WIRE 16 -1 (-4925 2600)(-4925 2550);
WIRE 16 -1 (-4925 2550)(-5050 2550);
WIRE 16 -1 (-4925 2650)(-4925 2600);
WIRE 16 -1 (-4925 2600)(-5050 2600);
WIRE 16 -1 (-4925 2700)(-4925 2650);
WIRE 16 -1 (-4925 2650)(-5050 2650);
WIRE 16 -1 (-4925 2750)(-4925 2700);
WIRE 16 -1 (-4925 2700)(-5050 2700);
WIRE 16 -1 (-4925 2800)(-4925 2750);
WIRE 16 -1 (-4925 2750)(-5050 2750);
WIRE 16 -1 (-5050 2800)(-4925 2800);
WIRE 16 -1 (-4925 2850)(-4925 2800);
WIRE 16 -1 (-4925 2900)(-4925 2850);
WIRE 16 -1 (-5050 2850)(-4925 2850);
WIRE 16 -1 (-4925 2950)(-4925 2900);
WIRE 16 -1 (-4925 2900)(-5050 2900);
WIRE 16 -1 (-4925 3000)(-4925 2950);
WIRE 16 -1 (-4925 2950)(-5050 2950);
WIRE 16 -1 (-4925 3050)(-4925 3000);
WIRE 16 -1 (-4925 3000)(-5050 3000);
WIRE 16 -1 (-4925 3100)(-4925 3050);
WIRE 16 -1 (-4925 3050)(-5050 3050);
WIRE 16 -1 (-4925 3150)(-4925 3100);
WIRE 16 -1 (-4925 3100)(-5050 3100);
WIRE 16 -1 (-4925 3200)(-4925 3150);
WIRE 16 -1 (-4925 3150)(-5050 3150);
WIRE 16 -1 (-5050 3200)(-4925 3200);
WIRE 16 -1 (-4925 3250)(-4925 3200);
WIRE 16 -1 (-5050 3250)(-4925 3250);
WIRE 16 -1 (-4925 3300)(-4925 3250);
WIRE 16 -1 (-4925 3350)(-4925 3300);
WIRE 16 -1 (-4925 3300)(-5050 3300);
WIRE 16 -1 (-4925 3400)(-4925 3350);
WIRE 16 -1 (-4925 3350)(-5050 3350);
WIRE 16 -1 (-4925 3450)(-4925 3400);
WIRE 16 -1 (-4925 3400)(-5050 3400);
WIRE 16 -1 (-4925 3500)(-4925 3450);
WIRE 16 -1 (-4925 3450)(-5050 3450);
WIRE 16 -1 (-4925 3550)(-4925 3500);
WIRE 16 -1 (-4925 3500)(-5050 3500);
WIRE 16 -1 (-4925 3600)(-4925 3550);
WIRE 16 -1 (-4925 3550)(-5050 3550);
WIRE 16 -1 (-4925 3650)(-4925 3600);
WIRE 16 -1 (-5050 3600)(-4925 3600);
WIRE 16 -1 (-5050 3650)(-4925 3650);
WIRE 16 -1 (-4925 3700)(-4925 3650);
WIRE 16 -1 (-4925 3750)(-4925 3700);
WIRE 16 -1 (-4925 3700)(-5050 3700);
WIRE 16 -1 (-4925 3800)(-4925 3750);
WIRE 16 -1 (-4925 3750)(-5050 3750);
WIRE 16 -1 (-4925 3850)(-4925 3800);
WIRE 16 -1 (-4925 3800)(-5050 3800);
WIRE 16 -1 (-4925 3900)(-4925 3850);
WIRE 16 -1 (-4925 3850)(-5050 3850);
WIRE 16 -1 (-4925 3950)(-4925 3900);
WIRE 16 -1 (-4925 3900)(-5050 3900);
WIRE 16 -1 (-4925 4000)(-4925 3950);
WIRE 16 -1 (-4925 3950)(-5050 3950);
WIRE 16 -1 (-5050 4000)(-4925 4000);
WIRE 16 -1 (-4925 4050)(-4925 4000);
WIRE 16 -1 (-5050 4050)(-4925 4050);
WIRE 16 -1 (-4925 4100)(-4925 4050);
WIRE 16 -1 (-4925 4150)(-4925 4100);
WIRE 16 -1 (-4925 4100)(-5050 4100);
WIRE 16 -1 (-4925 4200)(-4925 4150);
WIRE 16 -1 (-4925 4150)(-5050 4150);
WIRE 16 -1 (-4925 4250)(-4925 4200);
WIRE 16 -1 (-4925 4200)(-5050 4200);
WIRE 16 -1 (-4925 4300)(-4925 4250);
WIRE 16 -1 (-4925 4250)(-5050 4250);
WIRE 16 -1 (-4925 4350)(-4925 4300);
WIRE 16 -1 (-4925 4300)(-5050 4300);
WIRE 16 -1 (-4925 4400)(-4925 4350);
WIRE 16 -1 (-4925 4350)(-5050 4350);
WIRE 16 -1 (-4925 4450)(-4925 4400);
WIRE 16 -1 (-5050 4400)(-4925 4400);
WIRE 16 -1 (-5050 4450)(-4925 4450);
WIRE 16 -1 (-4925 4500)(-4925 4450);
WIRE 16 -1 (-4925 4550)(-4925 4500);
WIRE 16 -1 (-4925 4500)(-5050 4500);
WIRE 16 -1 (-4925 4600)(-4925 4550);
WIRE 16 -1 (-4925 4550)(-5050 4550);
WIRE 16 -1 (-4925 4650)(-4925 4600);
WIRE 16 -1 (-4925 4600)(-5050 4600);
WIRE 16 -1 (-4925 4700)(-4925 4650);
WIRE 16 -1 (-4925 4650)(-5050 4650);
WIRE 16 -1 (-4925 4750)(-4925 4700);
WIRE 16 -1 (-4925 4700)(-5050 4700);
WIRE 16 -1 (-4925 4800)(-4925 4750);
WIRE 16 -1 (-4925 4750)(-5050 4750);
WIRE 16 -1 (-5050 4800)(-4925 4800);
WIRE 16 -1 (-4925 4850)(-4925 4800);
WIRE 16 -1 (-5050 4850)(-4925 4850);
WIRE 16 -1 (-4925 4900)(-4925 4850);
WIRE 16 -1 (-4925 4950)(-4925 4900);
WIRE 16 -1 (-4925 4900)(-5050 4900);
WIRE 16 -1 (-4925 5000)(-4925 4950);
WIRE 16 -1 (-4925 4950)(-5050 4950);
WIRE 16 -1 (-4925 5050)(-4925 5000);
WIRE 16 -1 (-4925 5000)(-5050 5000);
WIRE 16 -1 (-4925 5100)(-4925 5050);
WIRE 16 -1 (-4925 5050)(-5050 5050);
WIRE 16 -1 (-4925 5150)(-4925 5100);
WIRE 16 -1 (-4925 5100)(-5050 5100);
WIRE 16 -1 (-4925 5200)(-4925 5150);
WIRE 16 -1 (-4925 5150)(-5050 5150);
WIRE 16 -1 (-5050 5200)(-4925 5200);
WIRE 16 -1 (-4925 5250)(-4925 5200);
WIRE 16 -1 (-5050 5250)(-4925 5250);
WIRE 16 -1 (-4925 5300)(-4925 5250);
WIRE 16 -1 (-4925 5350)(-4925 5300);
WIRE 16 -1 (-4925 5300)(-5050 5300);
WIRE 16 -1 (-4925 5400)(-4925 5350);
WIRE 16 -1 (-4925 5350)(-5050 5350);
WIRE 16 -1 (-4925 5450)(-4925 5400);
WIRE 16 -1 (-4925 5400)(-5050 5400);
WIRE 16 -1 (-4925 5500)(-4925 5450);
WIRE 16 -1 (-4925 5450)(-5050 5450);
WIRE 16 -1 (-4925 5550)(-4925 5500);
WIRE 16 -1 (-4925 5500)(-5050 5500);
WIRE 16 -1 (-4925 5600)(-4925 5550);
WIRE 16 -1 (-4925 5550)(-5050 5550);
WIRE 16 -1 (-5050 5600)(-4925 5600);
WIRE 16 -1 (-4925 5650)(-4925 5600);
WIRE 16 -1 (-4925 5700)(-4925 5650);
WIRE 16 -1 (-5050 5650)(-4925 5650);
WIRE 16 -1 (-4925 5750)(-4925 5700);
WIRE 16 -1 (-4925 5700)(-5050 5700);
WIRE 16 -1 (-4925 5800)(-4925 5750);
WIRE 16 -1 (-4925 5750)(-5050 5750);
WIRE 16 -1 (-4925 5850)(-4925 5800);
WIRE 16 -1 (-4925 5800)(-5050 5800);
WIRE 16 -1 (-4925 5900)(-4925 5850);
WIRE 16 -1 (-4925 5850)(-5050 5850);
WIRE 16 -1 (-4925 5950)(-4925 5900);
WIRE 16 -1 (-4925 5900)(-5050 5900);
WIRE 16 -1 (-4925 6000)(-4925 5950);
WIRE 16 -1 (-4925 5950)(-5050 5950);
WIRE 16 -1 (-5050 6000)(-4925 6000);
WIRE 16 -1 (-4925 6050)(-4925 6000);
WIRE 16 -1 (-5050 6050)(-4925 6050);
WIRE 16 -1 (-4925 6100)(-4925 6050);
WIRE 16 -1 (-5050 6100)(-4925 6100);
WIRE 16 -1 (-4925 6150)(-4925 6100);
WIRE 16 -1 (-4925 6200)(-4925 6150);
WIRE 16 -1 (-5050 6150)(-4925 6150);
WIRE 16 -1 (-5050 6200)(-4925 6200);
WIRE 16 -1 (-4925 6250)(-4925 6200);
WIRE 16 -1 (-5050 6250)(-4925 6250);
WIRE 16 -1 (-4925 6300)(-4925 6250);
WIRE 16 -1 (-5050 6300)(-4925 6300);
WIRE 16 -1 (-4775 575)(-4650 575);
WIRE 16 -1 (-4775 625)(-4775 575);
WIRE 16 -1 (-4775 575)(-4775 525);
WIRE 16 -1 (-4775 625)(-4650 625);
WIRE 16 -1 (-4775 675)(-4775 625);
WIRE 16 -1 (-4775 675)(-4650 675);
WIRE 16 -1 (-4775 725)(-4775 675);
WIRE 16 -1 (-4775 775)(-4775 725);
WIRE 16 -1 (-4650 725)(-4775 725);
WIRE 16 -1 (-4775 775)(-4650 775);
WIRE 16 -1 (-4775 825)(-4775 775);
WIRE 16 -1 (-4775 825)(-4650 825);
WIRE 16 -1 (-4775 875)(-4775 825);
WIRE 16 -1 (-4775 875)(-4650 875);
WIRE 16 -1 (-4775 925)(-4775 875);
WIRE 16 -1 (-4775 925)(-4650 925);
WIRE 16 -1 (-4775 975)(-4775 925);
WIRE 16 -1 (-4775 1025)(-4775 975);
WIRE 16 -1 (-4650 975)(-4775 975);
WIRE 16 -1 (-4775 1025)(-4650 1025);
WIRE 16 -1 (-4775 1075)(-4775 1025);
WIRE 16 -1 (-4775 1075)(-4650 1075);
WIRE 16 -1 (-4775 1125)(-4775 1075);
WIRE 16 -1 (-4775 1125)(-4650 1125);
WIRE 16 -1 (-4775 1175)(-4775 1125);
WIRE 16 -1 (-4775 1175)(-4650 1175);
WIRE 16 -1 (-4775 1225)(-4775 1175);
WIRE 16 -1 (-4775 1225)(-4650 1225);
WIRE 16 -1 (-4775 1275)(-4775 1225);
WIRE 16 -1 (-4775 1325)(-4775 1275);
WIRE 16 -1 (-4650 1275)(-4775 1275);
WIRE 16 -1 (-4775 1325)(-4650 1325);
WIRE 16 -1 (-4775 1375)(-4775 1325);
WIRE 16 -1 (-4775 1375)(-4650 1375);
WIRE 16 -1 (-4775 1425)(-4775 1375);
WIRE 16 -1 (-4775 1425)(-4650 1425);
WIRE 16 -1 (-4775 1475)(-4775 1425);
WIRE 16 -1 (-4775 1475)(-4650 1475);
WIRE 16 -1 (-4775 1525)(-4775 1475);
WIRE 16 -1 (-4775 1575)(-4775 1525);
WIRE 16 -1 (-4650 1525)(-4775 1525);
WIRE 16 -1 (-4775 1575)(-4650 1575);
WIRE 16 -1 (-4775 1625)(-4775 1575);
WIRE 16 -1 (-4775 1625)(-4650 1625);
WIRE 16 -1 (-4775 1675)(-4775 1625);
WIRE 16 -1 (-4775 1675)(-4650 1675);
WIRE 16 -1 (-4775 1725)(-4775 1675);
WIRE 16 -1 (-4775 1725)(-4650 1725);
WIRE 16 -1 (-4775 1775)(-4775 1725);
WIRE 16 -1 (-4775 1825)(-4775 1775);
WIRE 16 -1 (-4650 1775)(-4775 1775);
WIRE 16 -1 (-4775 1825)(-4650 1825);
WIRE 16 -1 (-4775 1875)(-4775 1825);
WIRE 16 -1 (-4775 1875)(-4650 1875);
WIRE 16 -1 (-4775 1925)(-4775 1875);
WIRE 16 -1 (-4775 1925)(-4650 1925);
WIRE 16 -1 (-4775 1975)(-4775 1925);
WIRE 16 -1 (-4775 1975)(-4650 1975);
WIRE 16 -1 (-4775 2025)(-4775 1975);
WIRE 16 -1 (-4775 2075)(-4775 2025);
WIRE 16 -1 (-4650 2025)(-4775 2025);
WIRE 16 -1 (-4775 2075)(-4650 2075);
WIRE 16 -1 (-4775 2125)(-4775 2075);
WIRE 16 -1 (-4775 2125)(-4650 2125);
WIRE 16 -1 (-4775 2175)(-4775 2125);
WIRE 16 -1 (-4775 2175)(-4650 2175);
WIRE 16 -1 (-4775 2225)(-4775 2175);
WIRE 16 -1 (-4775 2225)(-4650 2225);
WIRE 16 -1 (-4775 2275)(-4775 2225);
WIRE 16 -1 (-4775 2325)(-4775 2275);
WIRE 16 -1 (-4650 2275)(-4775 2275);
WIRE 16 -1 (-4775 2325)(-4650 2325);
WIRE 16 -1 (-4775 2375)(-4775 2325);
WIRE 16 -1 (-4775 2375)(-4650 2375);
WIRE 16 -1 (-4775 2425)(-4775 2375);
WIRE 16 -1 (-4775 2425)(-4650 2425);
WIRE 16 -1 (-4775 2475)(-4775 2425);
WIRE 16 -1 (-4775 2475)(-4650 2475);
WIRE 16 -1 (-4775 2525)(-4775 2475);
WIRE 16 -1 (-4775 2575)(-4775 2525);
WIRE 16 -1 (-4650 2525)(-4775 2525);
WIRE 16 -1 (-4775 2575)(-4650 2575);
WIRE 16 -1 (-4775 2625)(-4775 2575);
WIRE 16 -1 (-4775 2625)(-4650 2625);
WIRE 16 -1 (-4775 2675)(-4775 2625);
WIRE 16 -1 (-4775 2675)(-4650 2675);
WIRE 16 -1 (-4775 2725)(-4775 2675);
WIRE 16 -1 (-4775 2725)(-4650 2725);
WIRE 16 -1 (-4775 2775)(-4775 2725);
WIRE 16 -1 (-4775 2825)(-4775 2775);
WIRE 16 -1 (-4650 2775)(-4775 2775);
WIRE 16 -1 (-4775 2825)(-4650 2825);
WIRE 16 -1 (-4775 2875)(-4775 2825);
WIRE 16 -1 (-4775 2875)(-4650 2875);
WIRE 16 -1 (-4775 2925)(-4775 2875);
WIRE 16 -1 (-4775 2925)(-4650 2925);
WIRE 16 -1 (-4775 2975)(-4775 2925);
WIRE 16 -1 (-4775 2975)(-4650 2975);
WIRE 16 -1 (-4775 3025)(-4775 2975);
WIRE 16 -1 (-4775 3075)(-4775 3025);
WIRE 16 -1 (-4650 3025)(-4775 3025);
WIRE 16 -1 (-4775 3075)(-4650 3075);
WIRE 16 -1 (-4775 3125)(-4775 3075);
WIRE 16 -1 (-4775 3125)(-4650 3125);
WIRE 16 -1 (-4775 3175)(-4775 3125);
WIRE 16 -1 (-4775 3175)(-4650 3175);
WIRE 16 -1 (-4775 3225)(-4775 3175);
WIRE 16 -1 (-4775 3225)(-4650 3225);
WIRE 16 -1 (-4775 3275)(-4775 3225);
WIRE 16 -1 (-4775 3275)(-4650 3275);
WIRE 16 -1 (-4775 3325)(-4775 3275);
WIRE 16 -1 (-4775 3375)(-4775 3325);
WIRE 16 -1 (-4650 3325)(-4775 3325);
WIRE 16 -1 (-4775 3375)(-4650 3375);
WIRE 16 -1 (-4775 3425)(-4775 3375);
WIRE 16 -1 (-4775 3425)(-4650 3425);
WIRE 16 -1 (-4775 3475)(-4775 3425);
WIRE 16 -1 (-4775 3475)(-4650 3475);
WIRE 16 -1 (-4775 3525)(-4775 3475);
WIRE 16 -1 (-4775 3525)(-4650 3525);
WIRE 16 -1 (-4775 3575)(-4775 3525);
WIRE 16 -1 (-4775 3625)(-4775 3575);
WIRE 16 -1 (-4650 3575)(-4775 3575);
WIRE 16 -1 (-4775 3625)(-4650 3625);
WIRE 16 -1 (-4775 3675)(-4775 3625);
WIRE 16 -1 (-4775 3675)(-4650 3675);
WIRE 16 -1 (-4775 3725)(-4775 3675);
WIRE 16 -1 (-4775 3725)(-4650 3725);
WIRE 16 -1 (-4775 3775)(-4775 3725);
WIRE 16 -1 (-4775 3775)(-4650 3775);
WIRE 16 -1 (-4775 3825)(-4775 3775);
WIRE 16 -1 (-4775 3875)(-4775 3825);
WIRE 16 -1 (-4650 3825)(-4775 3825);
WIRE 16 -1 (-4775 3875)(-4650 3875);
WIRE 16 -1 (-4775 3925)(-4775 3875);
WIRE 16 -1 (-4775 3925)(-4650 3925);
WIRE 16 -1 (-4775 3975)(-4775 3925);
WIRE 16 -1 (-4775 3975)(-4650 3975);
WIRE 16 -1 (-4775 4025)(-4775 3975);
WIRE 16 -1 (-4775 4025)(-4650 4025);
WIRE 16 -1 (-4775 4075)(-4775 4025);
WIRE 16 -1 (-4775 4125)(-4775 4075);
WIRE 16 -1 (-4650 4075)(-4775 4075);
WIRE 16 -1 (-4775 4125)(-4650 4125);
WIRE 16 -1 (-4775 4175)(-4775 4125);
WIRE 16 -1 (-4775 4175)(-4650 4175);
WIRE 16 -1 (-4775 4225)(-4775 4175);
WIRE 16 -1 (-4775 4225)(-4650 4225);
WIRE 16 -1 (-4775 4275)(-4775 4225);
WIRE 16 -1 (-4775 4275)(-4650 4275);
WIRE 16 -1 (-4775 4325)(-4775 4275);
WIRE 16 -1 (-4775 4375)(-4775 4325);
WIRE 16 -1 (-4650 4325)(-4775 4325);
WIRE 16 -1 (-4775 4375)(-4650 4375);
WIRE 16 -1 (-4775 4425)(-4775 4375);
WIRE 16 -1 (-4775 4425)(-4650 4425);
WIRE 16 -1 (-4775 4475)(-4775 4425);
WIRE 16 -1 (-4775 4475)(-4650 4475);
WIRE 16 -1 (-4775 4525)(-4775 4475);
WIRE 16 -1 (-4775 4525)(-4650 4525);
WIRE 16 -1 (-4775 4575)(-4775 4525);
WIRE 16 -1 (-4775 4625)(-4775 4575);
WIRE 16 -1 (-4650 4575)(-4775 4575);
WIRE 16 -1 (-4775 4625)(-4650 4625);
WIRE 16 -1 (-4775 4675)(-4775 4625);
WIRE 16 -1 (-4775 4675)(-4650 4675);
WIRE 16 -1 (-4775 4725)(-4775 4675);
WIRE 16 -1 (-4775 4725)(-4650 4725);
WIRE 16 -1 (-4775 4775)(-4775 4725);
WIRE 16 -1 (-4775 4775)(-4650 4775);
WIRE 16 -1 (-4775 4825)(-4775 4775);
WIRE 16 -1 (-4775 4875)(-4775 4825);
WIRE 16 -1 (-4650 4825)(-4775 4825);
WIRE 16 -1 (-4775 4875)(-4650 4875);
WIRE 16 -1 (-4775 4925)(-4775 4875);
WIRE 16 -1 (-4775 4925)(-4650 4925);
WIRE 16 -1 (-4775 4975)(-4775 4925);
WIRE 16 -1 (-4775 4975)(-4650 4975);
WIRE 16 -1 (-4775 5025)(-4775 4975);
WIRE 16 -1 (-4775 5025)(-4650 5025);
WIRE 16 -1 (-4775 5075)(-4775 5025);
WIRE 16 -1 (-4775 5125)(-4775 5075);
WIRE 16 -1 (-4650 5075)(-4775 5075);
WIRE 16 -1 (-4775 5125)(-4650 5125);
WIRE 16 -1 (-4775 5175)(-4775 5125);
WIRE 16 -1 (-4775 5175)(-4650 5175);
WIRE 16 -1 (-4775 5225)(-4775 5175);
WIRE 16 -1 (-4775 5225)(-4650 5225);
WIRE 16 -1 (-4775 5275)(-4775 5225);
WIRE 16 -1 (-4775 5275)(-4650 5275);
WIRE 16 -1 (-4775 5325)(-4775 5275);
WIRE 16 -1 (-4775 5325)(-4650 5325);
WIRE 16 -1 (-4775 5375)(-4775 5325);
WIRE 16 -1 (-4775 5425)(-4775 5375);
WIRE 16 -1 (-4650 5375)(-4775 5375);
WIRE 16 -1 (-4775 5425)(-4650 5425);
WIRE 16 -1 (-4775 5475)(-4775 5425);
WIRE 16 -1 (-4775 5475)(-4650 5475);
WIRE 16 -1 (-4775 5525)(-4775 5475);
WIRE 16 -1 (-4775 5525)(-4650 5525);
WIRE 16 -1 (-4775 5575)(-4775 5525);
WIRE 16 -1 (-4775 5575)(-4650 5575);
WIRE 16 -1 (-4775 5625)(-4775 5575);
WIRE 16 -1 (-4775 5675)(-4775 5625);
WIRE 16 -1 (-4650 5625)(-4775 5625);
WIRE 16 -1 (-4775 5675)(-4650 5675);
WIRE 16 -1 (-4775 5725)(-4775 5675);
WIRE 16 -1 (-4775 5725)(-4650 5725);
WIRE 16 -1 (-4775 5775)(-4775 5725);
WIRE 16 -1 (-4775 5775)(-4650 5775);
WIRE 16 -1 (-4775 5825)(-4775 5775);
WIRE 16 -1 (-4775 5825)(-4650 5825);
WIRE 16 -1 (-4775 5875)(-4775 5825);
WIRE 16 -1 (-4775 5925)(-4775 5875);
WIRE 16 -1 (-4650 5875)(-4775 5875);
WIRE 16 -1 (-4775 5925)(-4650 5925);
WIRE 16 -1 (-4775 5975)(-4775 5925);
WIRE 16 -1 (-4775 5975)(-4650 5975);
WIRE 16 -1 (-4775 6025)(-4775 5975);
WIRE 16 -1 (-4775 6025)(-4650 6025);
WIRE 16 -1 (-4775 6075)(-4775 6025);
WIRE 16 -1 (-4775 6075)(-4650 6075);
WIRE 16 -1 (-4775 6125)(-4775 6075);
WIRE 16 -1 (-4775 6175)(-4775 6125);
WIRE 16 -1 (-4650 6125)(-4775 6125);
WIRE 16 -1 (-4775 6175)(-4650 6175);
WIRE 16 -1 (-4775 6225)(-4775 6175);
WIRE 16 -1 (-4775 6225)(-4650 6225);
WIRE 16 -1 (-4775 6275)(-4775 6225);
WIRE 16 -1 (-4775 6275)(-4650 6275);
WIRE 16 -1 (-4775 6325)(-4775 6275);
WIRE 16 -1 (-4775 6325)(-4650 6325);
WIRE 16 -1 (-4775 6375)(-4775 6325);
WIRE 16 -1 (-4775 6375)(-4650 6375);
WIRE 16 -1 (-3425 625)(-3425 575);
WIRE 16 -1 (-3425 675)(-3425 625);
WIRE 16 -1 (-3425 625)(-3550 625);
WIRE 16 -1 (-3425 575)(-3425 550);
WIRE 16 -1 (-3425 575)(-3550 575);
WIRE 16 -1 (-3425 725)(-3425 675);
WIRE 16 -1 (-3425 675)(-3550 675);
WIRE 16 -1 (-3425 775)(-3425 725);
WIRE 16 -1 (-3425 725)(-3550 725);
WIRE 16 -1 (-3425 825)(-3425 775);
WIRE 16 -1 (-3425 775)(-3550 775);
WIRE 16 -1 (-3550 825)(-3425 825);
WIRE 16 -1 (-3425 875)(-3425 825);
WIRE 16 -1 (-3550 875)(-3425 875);
WIRE 16 -1 (-3425 925)(-3425 875);
WIRE 16 -1 (-3425 975)(-3425 925);
WIRE 16 -1 (-3425 925)(-3550 925);
WIRE 16 -1 (-3425 1025)(-3425 975);
WIRE 16 -1 (-3425 975)(-3550 975);
WIRE 16 -1 (-3425 1075)(-3425 1025);
WIRE 16 -1 (-3425 1025)(-3550 1025);
WIRE 16 -1 (-3425 1125)(-3425 1075);
WIRE 16 -1 (-3425 1075)(-3550 1075);
WIRE 16 -1 (-3425 1175)(-3425 1125);
WIRE 16 -1 (-3425 1125)(-3550 1125);
WIRE 16 -1 (-3425 1225)(-3425 1175);
WIRE 16 -1 (-3425 1175)(-3550 1175);
WIRE 16 -1 (-3550 1225)(-3425 1225);
WIRE 16 -1 (-3425 1275)(-3425 1225);
WIRE 16 -1 (-3550 1275)(-3425 1275);
WIRE 16 -1 (-3425 1325)(-3425 1275);
WIRE 16 -1 (-3425 1375)(-3425 1325);
WIRE 16 -1 (-3425 1325)(-3550 1325);
WIRE 16 -1 (-3425 1425)(-3425 1375);
WIRE 16 -1 (-3425 1375)(-3550 1375);
WIRE 16 -1 (-3425 1475)(-3425 1425);
WIRE 16 -1 (-3425 1425)(-3550 1425);
WIRE 16 -1 (-3425 1525)(-3425 1475);
WIRE 16 -1 (-3425 1475)(-3550 1475);
WIRE 16 -1 (-3425 1575)(-3425 1525);
WIRE 16 -1 (-3425 1525)(-3550 1525);
WIRE 16 -1 (-3425 1625)(-3425 1575);
WIRE 16 -1 (-3425 1575)(-3550 1575);
WIRE 16 -1 (-3550 1625)(-3425 1625);
WIRE 16 -1 (-3425 1675)(-3425 1625);
WIRE 16 -1 (-3550 1675)(-3425 1675);
WIRE 16 -1 (-3425 1725)(-3425 1675);
WIRE 16 -1 (-3425 1775)(-3425 1725);
WIRE 16 -1 (-3425 1725)(-3550 1725);
WIRE 16 -1 (-3425 1825)(-3425 1775);
WIRE 16 -1 (-3425 1775)(-3550 1775);
WIRE 16 -1 (-3425 1875)(-3425 1825);
WIRE 16 -1 (-3425 1825)(-3550 1825);
WIRE 16 -1 (-3425 1925)(-3425 1875);
WIRE 16 -1 (-3425 1875)(-3550 1875);
WIRE 16 -1 (-3425 1975)(-3425 1925);
WIRE 16 -1 (-3425 1925)(-3550 1925);
WIRE 16 -1 (-3425 2025)(-3425 1975);
WIRE 16 -1 (-3425 1975)(-3550 1975);
WIRE 16 -1 (-3550 2025)(-3425 2025);
WIRE 16 -1 (-3425 2075)(-3425 2025);
WIRE 16 -1 (-3425 2125)(-3425 2075);
WIRE 16 -1 (-3550 2075)(-3425 2075);
WIRE 16 -1 (-3425 2175)(-3425 2125);
WIRE 16 -1 (-3425 2125)(-3550 2125);
WIRE 16 -1 (-3425 2225)(-3425 2175);
WIRE 16 -1 (-3425 2175)(-3550 2175);
WIRE 16 -1 (-3425 2275)(-3425 2225);
WIRE 16 -1 (-3425 2225)(-3550 2225);
WIRE 16 -1 (-3425 2325)(-3425 2275);
WIRE 16 -1 (-3425 2275)(-3550 2275);
WIRE 16 -1 (-3425 2375)(-3425 2325);
WIRE 16 -1 (-3425 2325)(-3550 2325);
WIRE 16 -1 (-3425 2425)(-3425 2375);
WIRE 16 -1 (-3425 2375)(-3550 2375);
WIRE 16 -1 (-3550 2425)(-3425 2425);
WIRE 16 -1 (-3425 2475)(-3425 2425);
WIRE 16 -1 (-3550 2475)(-3425 2475);
WIRE 16 -1 (-3425 2525)(-3425 2475);
WIRE 16 -1 (-3425 2575)(-3425 2525);
WIRE 16 -1 (-3425 2525)(-3550 2525);
WIRE 16 -1 (-3425 2625)(-3425 2575);
WIRE 16 -1 (-3425 2575)(-3550 2575);
WIRE 16 -1 (-3425 2675)(-3425 2625);
WIRE 16 -1 (-3425 2625)(-3550 2625);
WIRE 16 -1 (-3425 2725)(-3425 2675);
WIRE 16 -1 (-3425 2675)(-3550 2675);
WIRE 16 -1 (-3425 2775)(-3425 2725);
WIRE 16 -1 (-3425 2725)(-3550 2725);
WIRE 16 -1 (-3425 2825)(-3425 2775);
WIRE 16 -1 (-3425 2775)(-3550 2775);
WIRE 16 -1 (-3425 2875)(-3425 2825);
WIRE 16 -1 (-3550 2825)(-3425 2825);
WIRE 16 -1 (-3550 2875)(-3425 2875);
WIRE 16 -1 (-3425 2925)(-3425 2875);
WIRE 16 -1 (-3425 2975)(-3425 2925);
WIRE 16 -1 (-3425 2925)(-3550 2925);
WIRE 16 -1 (-3425 3025)(-3425 2975);
WIRE 16 -1 (-3425 2975)(-3550 2975);
WIRE 16 -1 (-3425 3075)(-3425 3025);
WIRE 16 -1 (-3425 3025)(-3550 3025);
WIRE 16 -1 (-3425 3125)(-3425 3075);
WIRE 16 -1 (-3425 3075)(-3550 3075);
WIRE 16 -1 (-3425 3175)(-3425 3125);
WIRE 16 -1 (-3425 3125)(-3550 3125);
WIRE 16 -1 (-3425 3225)(-3425 3175);
WIRE 16 -1 (-3425 3175)(-3550 3175);
WIRE 16 -1 (-3550 3225)(-3425 3225);
WIRE 16 -1 (-3425 3275)(-3425 3225);
WIRE 16 -1 (-3550 3275)(-3425 3275);
WIRE 16 -1 (-3425 3325)(-3425 3275);
WIRE 16 -1 (-3425 3375)(-3425 3325);
WIRE 16 -1 (-3425 3325)(-3550 3325);
WIRE 16 -1 (-3425 3425)(-3425 3375);
WIRE 16 -1 (-3425 3375)(-3550 3375);
WIRE 16 -1 (-3425 3475)(-3425 3425);
WIRE 16 -1 (-3425 3425)(-3550 3425);
WIRE 16 -1 (-3425 3525)(-3425 3475);
WIRE 16 -1 (-3425 3475)(-3550 3475);
WIRE 16 -1 (-3425 3575)(-3425 3525);
WIRE 16 -1 (-3425 3525)(-3550 3525);
WIRE 16 -1 (-3425 3625)(-3425 3575);
WIRE 16 -1 (-3425 3575)(-3550 3575);
WIRE 16 -1 (-3425 3675)(-3425 3625);
WIRE 16 -1 (-3550 3625)(-3425 3625);
WIRE 16 -1 (-3550 3675)(-3425 3675);
WIRE 16 -1 (-3425 3725)(-3425 3675);
WIRE 16 -1 (-3425 3775)(-3425 3725);
WIRE 16 -1 (-3425 3725)(-3550 3725);
WIRE 16 -1 (-3425 3825)(-3425 3775);
WIRE 16 -1 (-3425 3775)(-3550 3775);
WIRE 16 -1 (-3425 3875)(-3425 3825);
WIRE 16 -1 (-3425 3825)(-3550 3825);
WIRE 16 -1 (-3425 3925)(-3425 3875);
WIRE 16 -1 (-3425 3875)(-3550 3875);
WIRE 16 -1 (-3425 3975)(-3425 3925);
WIRE 16 -1 (-3425 3925)(-3550 3925);
WIRE 16 -1 (-3425 4025)(-3425 3975);
WIRE 16 -1 (-3425 3975)(-3550 3975);
WIRE 16 -1 (-3550 4025)(-3425 4025);
WIRE 16 -1 (-3425 4075)(-3425 4025);
WIRE 16 -1 (-3550 4075)(-3425 4075);
WIRE 16 -1 (-3425 4125)(-3425 4075);
WIRE 16 -1 (-3425 4175)(-3425 4125);
WIRE 16 -1 (-3425 4125)(-3550 4125);
WIRE 16 -1 (-3425 4225)(-3425 4175);
WIRE 16 -1 (-3425 4175)(-3550 4175);
WIRE 16 -1 (-3425 4275)(-3425 4225);
WIRE 16 -1 (-3425 4225)(-3550 4225);
WIRE 16 -1 (-3425 4325)(-3425 4275);
WIRE 16 -1 (-3425 4275)(-3550 4275);
WIRE 16 -1 (-3425 4375)(-3425 4325);
WIRE 16 -1 (-3425 4325)(-3550 4325);
WIRE 16 -1 (-3425 4425)(-3425 4375);
WIRE 16 -1 (-3425 4375)(-3550 4375);
WIRE 16 -1 (-3550 4425)(-3425 4425);
WIRE 16 -1 (-3425 4475)(-3425 4425);
WIRE 16 -1 (-3550 4475)(-3425 4475);
WIRE 16 -1 (-3425 4525)(-3425 4475);
WIRE 16 -1 (-3425 4575)(-3425 4525);
WIRE 16 -1 (-3425 4525)(-3550 4525);
WIRE 16 -1 (-3425 4625)(-3425 4575);
WIRE 16 -1 (-3425 4575)(-3550 4575);
WIRE 16 -1 (-3425 4675)(-3425 4625);
WIRE 16 -1 (-3425 4625)(-3550 4625);
WIRE 16 -1 (-3425 4725)(-3425 4675);
WIRE 16 -1 (-3425 4675)(-3550 4675);
WIRE 16 -1 (-3425 4775)(-3425 4725);
WIRE 16 -1 (-3425 4725)(-3550 4725);
WIRE 16 -1 (-3425 4825)(-3425 4775);
WIRE 16 -1 (-3425 4775)(-3550 4775);
WIRE 16 -1 (-3550 4825)(-3425 4825);
WIRE 16 -1 (-3425 4875)(-3425 4825);
WIRE 16 -1 (-3425 4925)(-3425 4875);
WIRE 16 -1 (-3550 4875)(-3425 4875);
WIRE 16 -1 (-3425 4975)(-3425 4925);
WIRE 16 -1 (-3425 4925)(-3550 4925);
WIRE 16 -1 (-3425 5025)(-3425 4975);
WIRE 16 -1 (-3425 4975)(-3550 4975);
WIRE 16 -1 (-3425 5075)(-3425 5025);
WIRE 16 -1 (-3425 5025)(-3550 5025);
WIRE 16 -1 (-3425 5125)(-3425 5075);
WIRE 16 -1 (-3425 5075)(-3550 5075);
WIRE 16 -1 (-3425 5175)(-3425 5125);
WIRE 16 -1 (-3425 5125)(-3550 5125);
WIRE 16 -1 (-3425 5225)(-3425 5175);
WIRE 16 -1 (-3425 5175)(-3550 5175);
WIRE 16 -1 (-3550 5225)(-3425 5225);
WIRE 16 -1 (-3425 5275)(-3425 5225);
WIRE 16 -1 (-3550 5275)(-3425 5275);
WIRE 16 -1 (-3425 5325)(-3425 5275);
WIRE 16 -1 (-3425 5375)(-3425 5325);
WIRE 16 -1 (-3425 5325)(-3550 5325);
WIRE 16 -1 (-3425 5425)(-3425 5375);
WIRE 16 -1 (-3425 5375)(-3550 5375);
WIRE 16 -1 (-3425 5475)(-3425 5425);
WIRE 16 -1 (-3425 5425)(-3550 5425);
WIRE 16 -1 (-3425 5525)(-3425 5475);
WIRE 16 -1 (-3425 5475)(-3550 5475);
WIRE 16 -1 (-3425 5575)(-3425 5525);
WIRE 16 -1 (-3425 5525)(-3550 5525);
WIRE 16 -1 (-3425 5625)(-3425 5575);
WIRE 16 -1 (-3425 5575)(-3550 5575);
WIRE 16 -1 (-3550 5625)(-3425 5625);
WIRE 16 -1 (-3425 5675)(-3425 5625);
WIRE 16 -1 (-3425 5725)(-3425 5675);
WIRE 16 -1 (-3550 5675)(-3425 5675);
WIRE 16 -1 (-3425 5775)(-3425 5725);
WIRE 16 -1 (-3425 5725)(-3550 5725);
WIRE 16 -1 (-3425 5825)(-3425 5775);
WIRE 16 -1 (-3425 5775)(-3550 5775);
WIRE 16 -1 (-3425 5875)(-3425 5825);
WIRE 16 -1 (-3425 5825)(-3550 5825);
WIRE 16 -1 (-3425 5925)(-3425 5875);
WIRE 16 -1 (-3425 5875)(-3550 5875);
WIRE 16 -1 (-3425 5975)(-3425 5925);
WIRE 16 -1 (-3425 5925)(-3550 5925);
WIRE 16 -1 (-3425 6025)(-3425 5975);
WIRE 16 -1 (-3425 5975)(-3550 5975);
WIRE 16 -1 (-3550 6025)(-3425 6025);
WIRE 16 -1 (-3425 6075)(-3425 6025);
WIRE 16 -1 (-3550 6075)(-3425 6075);
WIRE 16 -1 (-3425 6125)(-3425 6075);
WIRE 16 -1 (-3550 6125)(-3425 6125);
WIRE 16 -1 (-3425 6175)(-3425 6125);
WIRE 16 -1 (-3425 6225)(-3425 6175);
WIRE 16 -1 (-3550 6175)(-3425 6175);
WIRE 16 -1 (-3550 6225)(-3425 6225);
WIRE 16 -1 (-3425 6275)(-3425 6225);
WIRE 16 -1 (-3550 6275)(-3425 6275);
WIRE 16 -1 (-3425 6325)(-3425 6275);
WIRE 16 -1 (-3550 6325)(-3425 6325);
WIRE 16 -1 (-3425 6375)(-3425 6325);
WIRE 16 -1 (-3550 6375)(-3425 6375);
WIRE 16 -1 (-3175 525)(-3275 525);
WIRE 16 -1 (-3275 575)(-3275 525);
WIRE 16 -1 (-3275 525)(-3275 475);
WIRE 16 -1 (-3175 575)(-3275 575);
WIRE 16 -1 (-3275 625)(-3275 575);
WIRE 16 -1 (-3175 625)(-3275 625);
WIRE 16 -1 (-3275 675)(-3275 625);
WIRE 16 -1 (-3175 675)(-3275 675);
WIRE 16 -1 (-3275 725)(-3275 675);
WIRE 16 -1 (-3275 775)(-3275 725);
WIRE 16 -1 (-3175 725)(-3275 725);
WIRE 16 -1 (-3175 775)(-3275 775);
WIRE 16 -1 (-3275 825)(-3275 775);
WIRE 16 -1 (-3175 825)(-3275 825);
WIRE 16 -1 (-3275 875)(-3275 825);
WIRE 16 -1 (-3175 875)(-3275 875);
WIRE 16 -1 (-3275 925)(-3275 875);
WIRE 16 -1 (-3175 925)(-3275 925);
WIRE 16 -1 (-3275 975)(-3275 925);
WIRE 16 -1 (-3275 1025)(-3275 975);
WIRE 16 -1 (-3275 975)(-3175 975);
WIRE 16 -1 (-3275 1025)(-3175 1025);
WIRE 16 -1 (-3275 1075)(-3275 1025);
WIRE 16 -1 (-3275 1075)(-3175 1075);
WIRE 16 -1 (-3275 1125)(-3275 1075);
WIRE 16 -1 (-3275 1125)(-3175 1125);
WIRE 16 -1 (-3275 1175)(-3275 1125);
WIRE 16 -1 (-3275 1175)(-3175 1175);
WIRE 16 -1 (-3275 1225)(-3275 1175);
WIRE 16 -1 (-3275 1225)(-3175 1225);
WIRE 16 -1 (-3275 1275)(-3275 1225);
WIRE 16 -1 (-3275 1325)(-3275 1275);
WIRE 16 -1 (-3175 1275)(-3275 1275);
WIRE 16 -1 (-3175 1325)(-3275 1325);
WIRE 16 -1 (-3275 1375)(-3275 1325);
WIRE 16 -1 (-3275 1375)(-3175 1375);
WIRE 16 -1 (-3275 1425)(-3275 1375);
WIRE 16 -1 (-3275 1425)(-3175 1425);
WIRE 16 -1 (-3275 1475)(-3275 1425);
WIRE 16 -1 (-3275 1475)(-3175 1475);
WIRE 16 -1 (-3275 1525)(-3275 1475);
WIRE 16 -1 (-3275 1575)(-3275 1525);
WIRE 16 -1 (-3275 1525)(-3175 1525);
WIRE 16 -1 (-3275 1575)(-3175 1575);
WIRE 16 -1 (-3275 1625)(-3275 1575);
WIRE 16 -1 (-3275 1625)(-3175 1625);
WIRE 16 -1 (-3275 1675)(-3275 1625);
WIRE 16 -1 (-3175 1675)(-3275 1675);
WIRE 16 -1 (-3275 1725)(-3275 1675);
WIRE 16 -1 (-3175 1725)(-3275 1725);
WIRE 16 -1 (-3275 1775)(-3275 1725);
WIRE 16 -1 (-3275 1825)(-3275 1775);
WIRE 16 -1 (-3275 1775)(-3175 1775);
WIRE 16 -1 (-3275 1825)(-3175 1825);
WIRE 16 -1 (-3275 1875)(-3275 1825);
WIRE 16 -1 (-3275 1875)(-3175 1875);
WIRE 16 -1 (-3275 1925)(-3275 1875);
WIRE 16 -1 (-3275 1925)(-3175 1925);
WIRE 16 -1 (-3275 1975)(-3275 1925);
WIRE 16 -1 (-3275 1975)(-3175 1975);
WIRE 16 -1 (-3275 2025)(-3275 1975);
WIRE 16 -1 (-3275 2075)(-3275 2025);
WIRE 16 -1 (-3275 2025)(-3175 2025);
WIRE 16 -1 (-3175 2075)(-3275 2075);
WIRE 16 -1 (-3275 2125)(-3275 2075);
WIRE 16 -1 (-3175 2125)(-3275 2125);
WIRE 16 -1 (-3275 2175)(-3275 2125);
WIRE 16 -1 (-3275 2175)(-3175 2175);
WIRE 16 -1 (-3275 2225)(-3275 2175);
WIRE 16 -1 (-3275 2225)(-3175 2225);
WIRE 16 -1 (-3275 2275)(-3275 2225);
WIRE 16 -1 (-3275 2325)(-3275 2275);
WIRE 16 -1 (-3275 2275)(-3175 2275);
WIRE 16 -1 (-3275 2325)(-3175 2325);
WIRE 16 -1 (-3275 2375)(-3275 2325);
WIRE 16 -1 (-3275 2375)(-3175 2375);
WIRE 16 -1 (-3275 2425)(-3275 2375);
WIRE 16 -1 (-3275 2425)(-3175 2425);
WIRE 16 -1 (-3275 2475)(-3275 2425);
WIRE 16 -1 (-3175 2475)(-3275 2475);
WIRE 16 -1 (-3275 2525)(-3275 2475);
WIRE 16 -1 (-3275 2575)(-3275 2525);
WIRE 16 -1 (-3175 2525)(-3275 2525);
WIRE 16 -1 (-3275 2575)(-3175 2575);
WIRE 16 -1 (-3275 2625)(-3275 2575);
WIRE 16 -1 (-3275 2625)(-3175 2625);
WIRE 16 -1 (-3275 2675)(-3275 2625);
WIRE 16 -1 (-3275 2675)(-3175 2675);
WIRE 16 -1 (-3275 2725)(-3275 2675);
WIRE 16 -1 (-3275 2725)(-3175 2725);
WIRE 16 -1 (-3275 2775)(-3275 2725);
WIRE 16 -1 (-3275 2825)(-3275 2775);
WIRE 16 -1 (-3275 2775)(-3175 2775);
WIRE 16 -1 (-3275 2825)(-3175 2825);
WIRE 16 -1 (-3275 2875)(-3275 2825);
WIRE 16 -1 (-3175 2875)(-3275 2875);
WIRE 16 -1 (-3275 2925)(-3275 2875);
WIRE 16 -1 (-3175 2925)(-3275 2925);
WIRE 16 -1 (-3275 2975)(-3275 2925);
WIRE 16 -1 (-3275 2975)(-3175 2975);
WIRE 16 -1 (-3275 3025)(-3275 2975);
WIRE 16 -1 (-3275 3075)(-3275 3025);
WIRE 16 -1 (-3275 3025)(-3175 3025);
WIRE 16 -1 (-3275 3075)(-3175 3075);
WIRE 16 -1 (-3275 3125)(-3275 3075);
WIRE 16 -1 (-3275 3125)(-3175 3125);
WIRE 16 -1 (-3275 3175)(-3275 3125);
WIRE 16 -1 (-3275 3175)(-3175 3175);
WIRE 16 -1 (-3275 3225)(-3275 3175);
WIRE 16 -1 (-3275 3225)(-3175 3225);
WIRE 16 -1 (-3275 3275)(-3275 3225);
WIRE 16 -1 (-3175 3275)(-3275 3275);
WIRE 16 -1 (-3275 3325)(-3275 3275);
WIRE 16 -1 (-3275 3375)(-3275 3325);
WIRE 16 -1 (-3175 3325)(-3275 3325);
WIRE 16 -1 (-3275 3375)(-3175 3375);
WIRE 16 -1 (-3275 3425)(-3275 3375);
WIRE 16 -1 (-3275 3425)(-3175 3425);
WIRE 16 -1 (-3275 3475)(-3275 3425);
WIRE 16 -1 (-3275 3475)(-3175 3475);
WIRE 16 -1 (-3275 3525)(-3275 3475);
WIRE 16 -1 (-3275 3525)(-3175 3525);
WIRE 16 -1 (-3275 3575)(-3275 3525);
WIRE 16 -1 (-3275 3625)(-3275 3575);
WIRE 16 -1 (-3275 3575)(-3175 3575);
WIRE 16 -1 (-3275 3625)(-3175 3625);
WIRE 16 -1 (-3275 3675)(-3275 3625);
WIRE 16 -1 (-3175 3675)(-3275 3675);
WIRE 16 -1 (-3275 3725)(-3275 3675);
WIRE 16 -1 (-3175 3725)(-3275 3725);
WIRE 16 -1 (-3275 3775)(-3275 3725);
WIRE 16 -1 (-3275 3775)(-3175 3775);
WIRE 16 -1 (-3275 3825)(-3275 3775);
WIRE 16 -1 (-3275 3875)(-3275 3825);
WIRE 16 -1 (-3275 3825)(-3175 3825);
WIRE 16 -1 (-3275 3875)(-3175 3875);
WIRE 16 -1 (-3275 3925)(-3275 3875);
WIRE 16 -1 (-3275 3925)(-3175 3925);
WIRE 16 -1 (-3275 3975)(-3275 3925);
WIRE 16 -1 (-3275 3975)(-3175 3975);
WIRE 16 -1 (-3275 4025)(-3275 3975);
WIRE 16 -1 (-3275 4025)(-3175 4025);
WIRE 16 -1 (-3275 4075)(-3275 4025);
WIRE 16 -1 (-3275 4125)(-3275 4075);
WIRE 16 -1 (-3175 4075)(-3275 4075);
WIRE 16 -1 (-3175 4125)(-3275 4125);
WIRE 16 -1 (-3275 4175)(-3275 4125);
WIRE 16 -1 (-3275 4175)(-3175 4175);
WIRE 16 -1 (-3275 4225)(-3275 4175);
WIRE 16 -1 (-3275 4225)(-3175 4225);
WIRE 16 -1 (-3275 4275)(-3275 4225);
WIRE 16 -1 (-3275 4275)(-3175 4275);
WIRE 16 -1 (-3275 4325)(-3275 4275);
WIRE 16 -1 (-3275 4375)(-3275 4325);
WIRE 16 -1 (-3275 4325)(-3175 4325);
WIRE 16 -1 (-3275 4375)(-3175 4375);
WIRE 16 -1 (-3275 4425)(-3275 4375);
WIRE 16 -1 (-3275 4425)(-3175 4425);
WIRE 16 -1 (-3275 4475)(-3275 4425);
WIRE 16 -1 (-3175 4475)(-3275 4475);
WIRE 16 -1 (-3275 4525)(-3275 4475);
WIRE 16 -1 (-3175 4525)(-3275 4525);
WIRE 16 -1 (-3275 4575)(-3275 4525);
WIRE 16 -1 (-3275 4625)(-3275 4575);
WIRE 16 -1 (-3275 4575)(-3175 4575);
WIRE 16 -1 (-3275 4625)(-3175 4625);
WIRE 16 -1 (-3275 4675)(-3275 4625);
WIRE 16 -1 (-3275 4675)(-3175 4675);
WIRE 16 -1 (-3275 4725)(-3275 4675);
WIRE 16 -1 (-3275 4725)(-3175 4725);
WIRE 16 -1 (-3275 4775)(-3275 4725);
WIRE 16 -1 (-3275 4775)(-3175 4775);
WIRE 16 -1 (-3275 4825)(-3275 4775);
WIRE 16 -1 (-3275 4875)(-3275 4825);
WIRE 16 -1 (-3275 4825)(-3175 4825);
WIRE 16 -1 (-3175 4875)(-3275 4875);
WIRE 16 -1 (-3275 4925)(-3275 4875);
WIRE 16 -1 (-3175 4925)(-3275 4925);
WIRE 16 -1 (-3275 4975)(-3275 4925);
WIRE 16 -1 (-3275 4975)(-3175 4975);
WIRE 16 -1 (-3275 5025)(-3275 4975);
WIRE 16 -1 (-3275 5025)(-3175 5025);
WIRE 16 -1 (-3275 5075)(-3275 5025);
WIRE 16 -1 (-3275 5125)(-3275 5075);
WIRE 16 -1 (-3275 5075)(-3175 5075);
WIRE 16 -1 (-3275 5125)(-3175 5125);
WIRE 16 -1 (-3275 5175)(-3275 5125);
WIRE 16 -1 (-3275 5175)(-3175 5175);
WIRE 16 -1 (-3275 5225)(-3275 5175);
WIRE 16 -1 (-3275 5225)(-3175 5225);
WIRE 16 -1 (-3275 5275)(-3275 5225);
WIRE 16 -1 (-3175 5275)(-3275 5275);
WIRE 16 -1 (-3275 5325)(-3275 5275);
WIRE 16 -1 (-3175 5325)(-3275 5325);
WIRE 16 -1 (-3275 5375)(-3275 5325);
WIRE 16 -1 (-3275 5425)(-3275 5375);
WIRE 16 -1 (-3275 5375)(-3175 5375);
WIRE 16 -1 (-3275 5425)(-3175 5425);
WIRE 16 -1 (-3275 5475)(-3275 5425);
WIRE 16 -1 (-3275 5475)(-3175 5475);
WIRE 16 -1 (-3275 5525)(-3275 5475);
WIRE 16 -1 (-3275 5525)(-3175 5525);
WIRE 16 -1 (-3275 5575)(-3275 5525);
WIRE 16 -1 (-3275 5575)(-3175 5575);
WIRE 16 -1 (-3275 5625)(-3275 5575);
WIRE 16 -1 (-3275 5675)(-3275 5625);
WIRE 16 -1 (-3275 5625)(-3175 5625);
WIRE 16 -1 (-3175 5675)(-3275 5675);
WIRE 16 -1 (-3275 5725)(-3275 5675);
WIRE 16 -1 (-3175 5725)(-3275 5725);
WIRE 16 -1 (-3275 5775)(-3275 5725);
WIRE 16 -1 (-3275 5775)(-3175 5775);
WIRE 16 -1 (-3275 5825)(-3275 5775);
WIRE 16 -1 (-3275 5825)(-3175 5825);
WIRE 16 -1 (-3275 5875)(-3275 5825);
WIRE 16 -1 (-3275 5925)(-3275 5875);
WIRE 16 -1 (-3275 5875)(-3175 5875);
WIRE 16 -1 (-3275 5925)(-3175 5925);
WIRE 16 -1 (-3275 5975)(-3275 5925);
WIRE 16 -1 (-3275 5975)(-3175 5975);
WIRE 16 -1 (-3275 6025)(-3275 5975);
WIRE 16 -1 (-3275 6025)(-3175 6025);
WIRE 16 -1 (-3275 6075)(-3275 6025);
WIRE 16 -1 (-3175 6075)(-3275 6075);
WIRE 16 -1 (-3275 6125)(-3275 6075);
WIRE 16 -1 (-3275 6175)(-3275 6125);
WIRE 16 -1 (-3175 6125)(-3275 6125);
WIRE 16 -1 (-3275 6175)(-3175 6175);
WIRE 16 -1 (-3275 6225)(-3275 6175);
WIRE 16 -1 (-3275 6225)(-3175 6225);
WIRE 16 -1 (-3275 6275)(-3275 6225);
WIRE 16 -1 (-3275 6275)(-3175 6275);
WIRE 16 -1 (-3275 6325)(-3275 6275);
WIRE 16 -1 (-3275 6325)(-3175 6325);
WIRE 16 -1 (-3275 6375)(-3275 6325);
WIRE 16 -1 (-3275 6375)(-3175 6375);
WIRE 16 -1 (-1950 575)(-1950 525);
WIRE 16 -1 (-1950 625)(-1950 575);
WIRE 16 -1 (-1950 575)(-2075 575);
WIRE 16 -1 (-1950 525)(-1950 500);
WIRE 16 -1 (-1950 525)(-2075 525);
WIRE 16 -1 (-1950 675)(-1950 625);
WIRE 16 -1 (-1950 625)(-2075 625);
WIRE 16 -1 (-1950 725)(-1950 675);
WIRE 16 -1 (-1950 675)(-2075 675);
WIRE 16 -1 (-1950 775)(-1950 725);
WIRE 16 -1 (-1950 725)(-2075 725);
WIRE 16 -1 (-2075 775)(-1950 775);
WIRE 16 -1 (-1950 825)(-1950 775);
WIRE 16 -1 (-2075 825)(-1950 825);
WIRE 16 -1 (-1950 875)(-1950 825);
WIRE 16 -1 (-1950 925)(-1950 875);
WIRE 16 -1 (-1950 875)(-2075 875);
WIRE 16 -1 (-1950 975)(-1950 925);
WIRE 16 -1 (-1950 925)(-2075 925);
WIRE 16 -1 (-1950 1025)(-1950 975);
WIRE 16 -1 (-1950 975)(-2075 975);
WIRE 16 -1 (-1950 1075)(-1950 1025);
WIRE 16 -1 (-1950 1025)(-2075 1025);
WIRE 16 -1 (-1950 1125)(-1950 1075);
WIRE 16 -1 (-1950 1075)(-2075 1075);
WIRE 16 -1 (-1950 1175)(-1950 1125);
WIRE 16 -1 (-1950 1125)(-2075 1125);
WIRE 16 -1 (-2075 1175)(-1950 1175);
WIRE 16 -1 (-1950 1225)(-1950 1175);
WIRE 16 -1 (-2075 1225)(-1950 1225);
WIRE 16 -1 (-1950 1275)(-1950 1225);
WIRE 16 -1 (-1950 1325)(-1950 1275);
WIRE 16 -1 (-1950 1275)(-2075 1275);
WIRE 16 -1 (-1950 1375)(-1950 1325);
WIRE 16 -1 (-1950 1325)(-2075 1325);
WIRE 16 -1 (-1950 1425)(-1950 1375);
WIRE 16 -1 (-1950 1375)(-2075 1375);
WIRE 16 -1 (-1950 1475)(-1950 1425);
WIRE 16 -1 (-1950 1425)(-2075 1425);
WIRE 16 -1 (-1950 1525)(-1950 1475);
WIRE 16 -1 (-1950 1475)(-2075 1475);
WIRE 16 -1 (-1950 1575)(-1950 1525);
WIRE 16 -1 (-1950 1525)(-2075 1525);
WIRE 16 -1 (-2075 1575)(-1950 1575);
WIRE 16 -1 (-1950 1625)(-1950 1575);
WIRE 16 -1 (-2075 1625)(-1950 1625);
WIRE 16 -1 (-1950 1675)(-1950 1625);
WIRE 16 -1 (-1950 1725)(-1950 1675);
WIRE 16 -1 (-1950 1675)(-2075 1675);
WIRE 16 -1 (-1950 1775)(-1950 1725);
WIRE 16 -1 (-1950 1725)(-2075 1725);
WIRE 16 -1 (-1950 1825)(-1950 1775);
WIRE 16 -1 (-1950 1775)(-2075 1775);
WIRE 16 -1 (-1950 1875)(-1950 1825);
WIRE 16 -1 (-1950 1825)(-2075 1825);
WIRE 16 -1 (-1950 1925)(-1950 1875);
WIRE 16 -1 (-1950 1875)(-2075 1875);
WIRE 16 -1 (-1950 1975)(-1950 1925);
WIRE 16 -1 (-1950 1925)(-2075 1925);
WIRE 16 -1 (-2075 1975)(-1950 1975);
WIRE 16 -1 (-1950 2025)(-1950 1975);
WIRE 16 -1 (-2075 2025)(-1950 2025);
WIRE 16 -1 (-1950 2075)(-1950 2025);
WIRE 16 -1 (-1950 2125)(-1950 2075);
WIRE 16 -1 (-1950 2075)(-2075 2075);
WIRE 16 -1 (-1950 2175)(-1950 2125);
WIRE 16 -1 (-1950 2125)(-2075 2125);
WIRE 16 -1 (-1950 2225)(-1950 2175);
WIRE 16 -1 (-1950 2175)(-2075 2175);
WIRE 16 -1 (-1950 2275)(-1950 2225);
WIRE 16 -1 (-1950 2225)(-2075 2225);
WIRE 16 -1 (-1950 2325)(-1950 2275);
WIRE 16 -1 (-1950 2275)(-2075 2275);
WIRE 16 -1 (-1950 2375)(-1950 2325);
WIRE 16 -1 (-1950 2325)(-2075 2325);
WIRE 16 -1 (-2075 2375)(-1950 2375);
WIRE 16 -1 (-1950 2425)(-1950 2375);
WIRE 16 -1 (-2075 2425)(-1950 2425);
WIRE 16 -1 (-1950 2475)(-1950 2425);
WIRE 16 -1 (-1950 2525)(-1950 2475);
WIRE 16 -1 (-1950 2475)(-2075 2475);
WIRE 16 -1 (-1950 2575)(-1950 2525);
WIRE 16 -1 (-1950 2525)(-2075 2525);
WIRE 16 -1 (-1950 2625)(-1950 2575);
WIRE 16 -1 (-1950 2575)(-2075 2575);
WIRE 16 -1 (-1950 2675)(-1950 2625);
WIRE 16 -1 (-1950 2625)(-2075 2625);
WIRE 16 -1 (-1950 2725)(-1950 2675);
WIRE 16 -1 (-1950 2675)(-2075 2675);
WIRE 16 -1 (-1950 2775)(-1950 2725);
WIRE 16 -1 (-1950 2725)(-2075 2725);
WIRE 16 -1 (-2075 2775)(-1950 2775);
WIRE 16 -1 (-1950 2825)(-1950 2775);
WIRE 16 -1 (-2075 2825)(-1950 2825);
WIRE 16 -1 (-1950 2875)(-1950 2825);
WIRE 16 -1 (-1950 2925)(-1950 2875);
WIRE 16 -1 (-1950 2875)(-2075 2875);
WIRE 16 -1 (-1950 2975)(-1950 2925);
WIRE 16 -1 (-1950 2925)(-2075 2925);
WIRE 16 -1 (-1950 3025)(-1950 2975);
WIRE 16 -1 (-1950 2975)(-2075 2975);
WIRE 16 -1 (-1950 3075)(-1950 3025);
WIRE 16 -1 (-1950 3025)(-2075 3025);
WIRE 16 -1 (-1950 3125)(-1950 3075);
WIRE 16 -1 (-1950 3075)(-2075 3075);
WIRE 16 -1 (-1950 3175)(-1950 3125);
WIRE 16 -1 (-1950 3125)(-2075 3125);
WIRE 16 -1 (-2075 3175)(-1950 3175);
WIRE 16 -1 (-1950 3225)(-1950 3175);
WIRE 16 -1 (-2075 3225)(-1950 3225);
WIRE 16 -1 (-1950 3275)(-1950 3225);
WIRE 16 -1 (-1950 3325)(-1950 3275);
WIRE 16 -1 (-1950 3275)(-2075 3275);
WIRE 16 -1 (-1950 3375)(-1950 3325);
WIRE 16 -1 (-1950 3325)(-2075 3325);
WIRE 16 -1 (-1950 3425)(-1950 3375);
WIRE 16 -1 (-1950 3375)(-2075 3375);
WIRE 16 -1 (-1950 3475)(-1950 3425);
WIRE 16 -1 (-1950 3425)(-2075 3425);
WIRE 16 -1 (-1950 3525)(-1950 3475);
WIRE 16 -1 (-1950 3475)(-2075 3475);
WIRE 16 -1 (-1950 3575)(-1950 3525);
WIRE 16 -1 (-1950 3525)(-2075 3525);
WIRE 16 -1 (-2075 3575)(-1950 3575);
WIRE 16 -1 (-1950 3625)(-1950 3575);
WIRE 16 -1 (-2075 3625)(-1950 3625);
WIRE 16 -1 (-1950 3675)(-1950 3625);
WIRE 16 -1 (-1950 3725)(-1950 3675);
WIRE 16 -1 (-1950 3675)(-2075 3675);
WIRE 16 -1 (-1950 3775)(-1950 3725);
WIRE 16 -1 (-1950 3725)(-2075 3725);
WIRE 16 -1 (-1950 3825)(-1950 3775);
WIRE 16 -1 (-1950 3775)(-2075 3775);
WIRE 16 -1 (-1950 3875)(-1950 3825);
WIRE 16 -1 (-1950 3825)(-2075 3825);
WIRE 16 -1 (-1950 3925)(-1950 3875);
WIRE 16 -1 (-1950 3875)(-2075 3875);
WIRE 16 -1 (-1950 3975)(-1950 3925);
WIRE 16 -1 (-1950 3925)(-2075 3925);
WIRE 16 -1 (-2075 3975)(-1950 3975);
WIRE 16 -1 (-1950 4025)(-1950 3975);
WIRE 16 -1 (-2075 4025)(-1950 4025);
WIRE 16 -1 (-1950 4075)(-1950 4025);
WIRE 16 -1 (-1950 4125)(-1950 4075);
WIRE 16 -1 (-1950 4075)(-2075 4075);
WIRE 16 -1 (-1950 4175)(-1950 4125);
WIRE 16 -1 (-1950 4125)(-2075 4125);
WIRE 16 -1 (-1950 4225)(-1950 4175);
WIRE 16 -1 (-1950 4175)(-2075 4175);
WIRE 16 -1 (-1950 4275)(-1950 4225);
WIRE 16 -1 (-1950 4225)(-2075 4225);
WIRE 16 -1 (-1950 4325)(-1950 4275);
WIRE 16 -1 (-1950 4275)(-2075 4275);
WIRE 16 -1 (-1950 4375)(-1950 4325);
WIRE 16 -1 (-1950 4325)(-2075 4325);
WIRE 16 -1 (-2075 4375)(-1950 4375);
WIRE 16 -1 (-1950 4425)(-1950 4375);
WIRE 16 -1 (-2075 4425)(-1950 4425);
WIRE 16 -1 (-1950 4475)(-1950 4425);
WIRE 16 -1 (-1950 4525)(-1950 4475);
WIRE 16 -1 (-1950 4475)(-2075 4475);
WIRE 16 -1 (-1950 4575)(-1950 4525);
WIRE 16 -1 (-1950 4525)(-2075 4525);
WIRE 16 -1 (-1950 4625)(-1950 4575);
WIRE 16 -1 (-1950 4575)(-2075 4575);
WIRE 16 -1 (-1950 4675)(-1950 4625);
WIRE 16 -1 (-1950 4625)(-2075 4625);
WIRE 16 -1 (-1950 4725)(-1950 4675);
WIRE 16 -1 (-1950 4675)(-2075 4675);
WIRE 16 -1 (-1950 4775)(-1950 4725);
WIRE 16 -1 (-1950 4725)(-2075 4725);
WIRE 16 -1 (-2075 4775)(-1950 4775);
WIRE 16 -1 (-1950 4825)(-1950 4775);
WIRE 16 -1 (-2075 4825)(-1950 4825);
WIRE 16 -1 (-1950 4875)(-1950 4825);
WIRE 16 -1 (-1950 4925)(-1950 4875);
WIRE 16 -1 (-1950 4875)(-2075 4875);
WIRE 16 -1 (-1950 4975)(-1950 4925);
WIRE 16 -1 (-1950 4925)(-2075 4925);
WIRE 16 -1 (-1950 5025)(-1950 4975);
WIRE 16 -1 (-1950 4975)(-2075 4975);
WIRE 16 -1 (-1950 5075)(-1950 5025);
WIRE 16 -1 (-1950 5025)(-2075 5025);
WIRE 16 -1 (-1950 5125)(-1950 5075);
WIRE 16 -1 (-1950 5075)(-2075 5075);
WIRE 16 -1 (-1950 5175)(-1950 5125);
WIRE 16 -1 (-1950 5125)(-2075 5125);
WIRE 16 -1 (-2075 5175)(-1950 5175);
WIRE 16 -1 (-1950 5225)(-1950 5175);
WIRE 16 -1 (-2075 5225)(-1950 5225);
WIRE 16 -1 (-1950 5275)(-1950 5225);
WIRE 16 -1 (-1950 5325)(-1950 5275);
WIRE 16 -1 (-1950 5275)(-2075 5275);
WIRE 16 -1 (-1950 5375)(-1950 5325);
WIRE 16 -1 (-1950 5325)(-2075 5325);
WIRE 16 -1 (-1950 5425)(-1950 5375);
WIRE 16 -1 (-1950 5375)(-2075 5375);
WIRE 16 -1 (-1950 5475)(-1950 5425);
WIRE 16 -1 (-1950 5425)(-2075 5425);
WIRE 16 -1 (-1950 5525)(-1950 5475);
WIRE 16 -1 (-1950 5475)(-2075 5475);
WIRE 16 -1 (-1950 5575)(-1950 5525);
WIRE 16 -1 (-1950 5525)(-2075 5525);
WIRE 16 -1 (-2075 5575)(-1950 5575);
WIRE 16 -1 (-1950 5625)(-1950 5575);
WIRE 16 -1 (-2075 5625)(-1950 5625);
WIRE 16 -1 (-1950 5675)(-1950 5625);
WIRE 16 -1 (-1950 5725)(-1950 5675);
WIRE 16 -1 (-1950 5675)(-2075 5675);
WIRE 16 -1 (-1950 5775)(-1950 5725);
WIRE 16 -1 (-1950 5725)(-2075 5725);
WIRE 16 -1 (-1950 5825)(-1950 5775);
WIRE 16 -1 (-1950 5775)(-2075 5775);
WIRE 16 -1 (-1950 5875)(-1950 5825);
WIRE 16 -1 (-1950 5825)(-2075 5825);
WIRE 16 -1 (-1950 5925)(-1950 5875);
WIRE 16 -1 (-1950 5875)(-2075 5875);
WIRE 16 -1 (-1950 5975)(-1950 5925);
WIRE 16 -1 (-1950 5925)(-2075 5925);
WIRE 16 -1 (-2075 5975)(-1950 5975);
WIRE 16 -1 (-1950 6025)(-1950 5975);
WIRE 16 -1 (-2075 6025)(-1950 6025);
WIRE 16 -1 (-1950 6075)(-1950 6025);
WIRE 16 -1 (-2075 6075)(-1950 6075);
WIRE 16 -1 (-1950 6125)(-1950 6075);
WIRE 16 -1 (-2075 6125)(-1950 6125);
WIRE 16 -1 (-1950 6175)(-1950 6125);
WIRE 16 -1 (-2075 6175)(-1950 6175);
WIRE 16 -1 (-1950 6225)(-1950 6175);
WIRE 16 -1 (-2075 6225)(-1950 6225);
WIRE 16 -1 (-1950 6275)(-1950 6225);
WIRE 16 -1 (-2075 6275)(-1950 6275);
WIRE 16 -1 (-1950 6325)(-1950 6275);
WIRE 16 -1 (-2075 6325)(-1950 6325);
WIRE 16 -1 (-1950 6375)(-1950 6325);
WIRE 16 -1 (-1950 6425)(-1950 6375);
WIRE 16 -1 (-1950 6375)(-2075 6375);
WIRE 16 -1 (-1950 6425)(-2075 6425);
WIRE 16 -1 (-1550 525)(-1650 525);
WIRE 16 -1 (-1650 575)(-1650 525);
WIRE 16 -1 (-1650 525)(-1650 500);
WIRE 16 -1 (-1550 575)(-1650 575);
WIRE 16 -1 (-1650 625)(-1650 575);
WIRE 16 -1 (-1650 675)(-1650 625);
WIRE 16 -1 (-1550 625)(-1650 625);
WIRE 16 -1 (-1550 675)(-1650 675);
WIRE 16 -1 (-1650 725)(-1650 675);
WIRE 16 -1 (-1650 775)(-1650 725);
WIRE 16 -1 (-1550 725)(-1650 725);
WIRE 16 -1 (-1550 775)(-1650 775);
WIRE 16 -1 (-1650 825)(-1650 775);
WIRE 16 -1 (-1550 825)(-1650 825);
WIRE 16 -1 (-1650 875)(-1650 825);
WIRE 16 -1 (-1650 925)(-1650 875);
WIRE 16 -1 (-1550 875)(-1650 875);
WIRE 16 -1 (-1550 925)(-1650 925);
WIRE 16 -1 (-1650 975)(-1650 925);
WIRE 16 -1 (-1650 1025)(-1650 975);
WIRE 16 -1 (-1550 975)(-1650 975);
WIRE 16 -1 (-1650 1025)(-1550 1025);
WIRE 16 -1 (-1650 1075)(-1650 1025);
WIRE 16 -1 (-1650 1075)(-1550 1075);
WIRE 16 -1 (-1650 1125)(-1650 1075);
WIRE 16 -1 (-1650 1175)(-1650 1125);
WIRE 16 -1 (-1650 1125)(-1550 1125);
WIRE 16 -1 (-1650 1175)(-1550 1175);
WIRE 16 -1 (-1650 1225)(-1650 1175);
WIRE 16 -1 (-1650 1225)(-1550 1225);
WIRE 16 -1 (-1650 1275)(-1650 1225);
WIRE 16 -1 (-1650 1325)(-1650 1275);
WIRE 16 -1 (-1650 1275)(-1550 1275);
WIRE 16 -1 (-1550 1325)(-1650 1325);
WIRE 16 -1 (-1650 1375)(-1650 1325);
WIRE 16 -1 (-1650 1425)(-1650 1375);
WIRE 16 -1 (-1550 1375)(-1650 1375);
WIRE 16 -1 (-1650 1425)(-1550 1425);
WIRE 16 -1 (-1650 1475)(-1650 1425);
WIRE 16 -1 (-1650 1475)(-1550 1475);
WIRE 16 -1 (-1650 1525)(-1650 1475);
WIRE 16 -1 (-1650 1575)(-1650 1525);
WIRE 16 -1 (-1650 1525)(-1550 1525);
WIRE 16 -1 (-1650 1575)(-1550 1575);
WIRE 16 -1 (-1650 1625)(-1650 1575);
WIRE 16 -1 (-1650 1675)(-1650 1625);
WIRE 16 -1 (-1650 1625)(-1550 1625);
WIRE 16 -1 (-1650 1675)(-1550 1675);
WIRE 16 -1 (-1650 1725)(-1650 1675);
WIRE 16 -1 (-1550 1725)(-1650 1725);
WIRE 16 -1 (-1650 1775)(-1650 1725);
WIRE 16 -1 (-1650 1825)(-1650 1775);
WIRE 16 -1 (-1550 1775)(-1650 1775);
WIRE 16 -1 (-1650 1825)(-1550 1825);
WIRE 16 -1 (-1650 1875)(-1650 1825);
WIRE 16 -1 (-1650 1925)(-1650 1875);
WIRE 16 -1 (-1650 1875)(-1550 1875);
WIRE 16 -1 (-1650 1925)(-1550 1925);
WIRE 16 -1 (-1650 1975)(-1650 1925);
WIRE 16 -1 (-1650 1975)(-1550 1975);
WIRE 16 -1 (-1650 2025)(-1650 1975);
WIRE 16 -1 (-1650 2075)(-1650 2025);
WIRE 16 -1 (-1650 2025)(-1550 2025);
WIRE 16 -1 (-1650 2075)(-1550 2075);
WIRE 16 -1 (-1650 2125)(-1650 2075);
WIRE 16 -1 (-1550 2125)(-1650 2125);
WIRE 16 -1 (-1650 2175)(-1650 2125);
WIRE 16 -1 (-1650 2225)(-1650 2175);
WIRE 16 -1 (-1550 2175)(-1650 2175);
WIRE 16 -1 (-1650 2225)(-1550 2225);
WIRE 16 -1 (-1650 2275)(-1650 2225);
WIRE 16 -1 (-1650 2325)(-1650 2275);
WIRE 16 -1 (-1650 2275)(-1550 2275);
WIRE 16 -1 (-1650 2325)(-1550 2325);
WIRE 16 -1 (-1650 2375)(-1650 2325);
WIRE 16 -1 (-1650 2375)(-1550 2375);
WIRE 16 -1 (-1650 2425)(-1650 2375);
WIRE 16 -1 (-1650 2475)(-1650 2425);
WIRE 16 -1 (-1650 2425)(-1550 2425);
WIRE 16 -1 (-1650 2475)(-1550 2475);
WIRE 16 -1 (-1650 2525)(-1650 2475);
WIRE 16 -1 (-1650 2575)(-1650 2525);
WIRE 16 -1 (-1550 2525)(-1650 2525);
WIRE 16 -1 (-1550 2575)(-1650 2575);
WIRE 16 -1 (-1650 2625)(-1650 2575);
WIRE 16 -1 (-1650 2625)(-1550 2625);
WIRE 16 -1 (-1650 2675)(-1650 2625);
WIRE 16 -1 (-1650 2725)(-1650 2675);
WIRE 16 -1 (-1650 2675)(-1550 2675);
WIRE 16 -1 (-1650 2725)(-1550 2725);
WIRE 16 -1 (-1650 2775)(-1650 2725);
WIRE 16 -1 (-1650 2825)(-1650 2775);
WIRE 16 -1 (-1650 2775)(-1550 2775);
WIRE 16 -1 (-1650 2825)(-1550 2825);
WIRE 16 -1 (-1650 2875)(-1650 2825);
WIRE 16 -1 (-1650 2875)(-1550 2875);
WIRE 16 -1 (-1650 2925)(-1650 2875);
WIRE 16 -1 (-1650 2975)(-1650 2925);
WIRE 16 -1 (-1550 2925)(-1650 2925);
WIRE 16 -1 (-1550 2975)(-1650 2975);
WIRE 16 -1 (-1650 3025)(-1650 2975);
WIRE 16 -1 (-1650 3075)(-1650 3025);
WIRE 16 -1 (-1650 3025)(-1550 3025);
WIRE 16 -1 (-1650 3075)(-1550 3075);
WIRE 16 -1 (-1650 3125)(-1650 3075);
WIRE 16 -1 (-1650 3125)(-1550 3125);
WIRE 16 -1 (-1650 3175)(-1650 3125);
WIRE 16 -1 (-1650 3225)(-1650 3175);
WIRE 16 -1 (-1650 3175)(-1550 3175);
WIRE 16 -1 (-1650 3225)(-1550 3225);
WIRE 16 -1 (-1650 3275)(-1650 3225);
WIRE 16 -1 (-1650 3275)(-1550 3275);
WIRE 16 -1 (-1650 3325)(-1650 3275);
WIRE 16 -1 (-1650 3375)(-1650 3325);
WIRE 16 -1 (-1550 3325)(-1650 3325);
WIRE 16 -1 (-1550 3375)(-1650 3375);
WIRE 16 -1 (-1650 3425)(-1650 3375);
WIRE 16 -1 (-1650 3475)(-1650 3425);
WIRE 16 -1 (-1650 3425)(-1550 3425);
WIRE 16 -1 (-1650 3475)(-1550 3475);
WIRE 16 -1 (-1650 3525)(-1650 3475);
WIRE 16 -1 (-1650 3525)(-1550 3525);
WIRE 16 -1 (-1650 3575)(-1650 3525);
WIRE 16 -1 (-1650 3625)(-1650 3575);
WIRE 16 -1 (-1650 3575)(-1550 3575);
WIRE 16 -1 (-1650 3625)(-1550 3625);
WIRE 16 -1 (-1650 3675)(-1650 3625);
WIRE 16 -1 (-1650 3725)(-1650 3675);
WIRE 16 -1 (-1650 3675)(-1550 3675);
WIRE 16 -1 (-1550 3725)(-1650 3725);
WIRE 16 -1 (-1650 3775)(-1650 3725);
WIRE 16 -1 (-1550 3775)(-1650 3775);
WIRE 16 -1 (-1650 3825)(-1650 3775);
WIRE 16 -1 (-1650 3875)(-1650 3825);
WIRE 16 -1 (-1650 3825)(-1550 3825);
WIRE 16 -1 (-1650 3875)(-1550 3875);
WIRE 16 -1 (-1650 3925)(-1650 3875);
WIRE 16 -1 (-1650 3975)(-1650 3925);
WIRE 16 -1 (-1650 3925)(-1550 3925);
WIRE 16 -1 (-1650 3975)(-1550 3975);
WIRE 16 -1 (-1650 4025)(-1650 3975);
WIRE 16 -1 (-1650 4025)(-1550 4025);
WIRE 16 -1 (-1650 4075)(-1650 4025);
WIRE 16 -1 (-1650 4125)(-1650 4075);
WIRE 16 -1 (-1650 4075)(-1550 4075);
WIRE 16 -1 (-1550 4125)(-1650 4125);
WIRE 16 -1 (-1650 4175)(-1650 4125);
WIRE 16 -1 (-1650 4225)(-1650 4175);
WIRE 16 -1 (-1550 4175)(-1650 4175);
WIRE 16 -1 (-1650 4225)(-1550 4225);
WIRE 16 -1 (-1650 4275)(-1650 4225);
WIRE 16 -1 (-1650 4275)(-1550 4275);
WIRE 16 -1 (-1650 4325)(-1650 4275);
WIRE 16 -1 (-1650 4375)(-1650 4325);
WIRE 16 -1 (-1650 4325)(-1550 4325);
WIRE 16 -1 (-1650 4375)(-1550 4375);
WIRE 16 -1 (-1650 4425)(-1650 4375);
WIRE 16 -1 (-1650 4425)(-1550 4425);
WIRE 16 -1 (-1650 4475)(-1650 4425);
WIRE 16 -1 (-1650 4525)(-1650 4475);
WIRE 16 -1 (-1650 4475)(-1550 4475);
WIRE 16 -1 (-1550 4525)(-1650 4525);
WIRE 16 -1 (-1650 4575)(-1650 4525);
WIRE 16 -1 (-1650 4625)(-1650 4575);
WIRE 16 -1 (-1550 4575)(-1650 4575);
WIRE 16 -1 (-1650 4625)(-1550 4625);
WIRE 16 -1 (-1650 4675)(-1650 4625);
WIRE 16 -1 (-1650 4675)(-1550 4675);
WIRE 16 -1 (-1650 4725)(-1650 4675);
WIRE 16 -1 (-1650 4775)(-1650 4725);
WIRE 16 -1 (-1650 4725)(-1550 4725);
WIRE 16 -1 (-1650 4775)(-1550 4775);
WIRE 16 -1 (-1650 4825)(-1650 4775);
WIRE 16 -1 (-1650 4875)(-1650 4825);
WIRE 16 -1 (-1650 4825)(-1550 4825);
WIRE 16 -1 (-1650 4875)(-1550 4875);
WIRE 16 -1 (-1650 4925)(-1650 4875);
WIRE 16 -1 (-1550 4925)(-1650 4925);
WIRE 16 -1 (-1650 4975)(-1650 4925);
WIRE 16 -1 (-1650 5025)(-1650 4975);
WIRE 16 -1 (-1550 4975)(-1650 4975);
WIRE 16 -1 (-1650 5025)(-1550 5025);
WIRE 16 -1 (-1650 5075)(-1650 5025);
WIRE 16 -1 (-1650 5125)(-1650 5075);
WIRE 16 -1 (-1650 5075)(-1550 5075);
WIRE 16 -1 (-1650 5125)(-1550 5125);
WIRE 16 -1 (-1650 5175)(-1650 5125);
WIRE 16 -1 (-1650 5175)(-1550 5175);
WIRE 16 -1 (-1650 5225)(-1650 5175);
WIRE 16 -1 (-1650 5275)(-1650 5225);
WIRE 16 -1 (-1650 5225)(-1550 5225);
WIRE 16 -1 (-1650 5275)(-1550 5275);
WIRE 16 -1 (-1650 5325)(-1650 5275);
WIRE 16 -1 (-1550 5325)(-1650 5325);
WIRE 16 -1 (-1650 5375)(-1650 5325);
WIRE 16 -1 (-1650 5425)(-1650 5375);
WIRE 16 -1 (-1550 5375)(-1650 5375);
WIRE 16 -1 (-1650 5425)(-1550 5425);
WIRE 16 -1 (-1650 5475)(-1650 5425);
WIRE 16 -1 (-1650 5525)(-1650 5475);
WIRE 16 -1 (-1650 5475)(-1550 5475);
WIRE 16 -1 (-1650 5525)(-1550 5525);
WIRE 16 -1 (-1650 5575)(-1650 5525);
WIRE 16 -1 (-1650 5575)(-1550 5575);
WIRE 16 -1 (-1650 5625)(-1650 5575);
WIRE 16 -1 (-1650 5675)(-1650 5625);
WIRE 16 -1 (-1650 5625)(-1550 5625);
WIRE 16 -1 (-1650 5675)(-1550 5675);
WIRE 16 -1 (-1650 5725)(-1650 5675);
WIRE 16 -1 (-1650 5775)(-1650 5725);
WIRE 16 -1 (-1550 5725)(-1650 5725);
WIRE 16 -1 (-1550 5775)(-1650 5775);
WIRE 16 -1 (-1650 5825)(-1650 5775);
WIRE 16 -1 (-1650 5825)(-1550 5825);
WIRE 16 -1 (-1650 5875)(-1650 5825);
WIRE 16 -1 (-1650 5925)(-1650 5875);
WIRE 16 -1 (-1650 5875)(-1550 5875);
WIRE 16 -1 (-1650 5925)(-1550 5925);
WIRE 16 -1 (-1650 5975)(-1650 5925);
WIRE 16 -1 (-1650 6025)(-1650 5975);
WIRE 16 -1 (-1650 5975)(-1550 5975);
WIRE 16 -1 (-1650 6025)(-1550 6025);
WIRE 16 -1 (-1650 6075)(-1650 6025);
WIRE 16 -1 (-1650 6075)(-1550 6075);
WIRE 16 -1 (-1650 6125)(-1650 6075);
WIRE 16 -1 (-1650 6175)(-1650 6125);
WIRE 16 -1 (-1550 6125)(-1650 6125);
WIRE 16 -1 (-1550 6175)(-1650 6175);
WIRE 16 -1 (-1650 6225)(-1650 6175);
WIRE 16 -1 (-1650 6275)(-1650 6225);
WIRE 16 -1 (-1650 6225)(-1550 6225);
WIRE 16 -1 (-1650 6275)(-1550 6275);
WIRE 16 -1 (-1650 6325)(-1650 6275);
WIRE 16 -1 (-1650 6325)(-1550 6325);
WIRE 16 -1 (-1650 6375)(-1650 6325);
WIRE 16 -1 (-1650 6425)(-1650 6375);
WIRE 16 -1 (-1650 6375)(-1550 6375);
WIRE 16 -1 (-1650 6425)(-1550 6425);
WIRE 16 -1 (-325 575)(-325 525);
WIRE 16 -1 (-325 625)(-325 575);
WIRE 16 -1 (-325 575)(-450 575);
WIRE 16 -1 (-325 525)(-450 525);
WIRE 16 -1 (-325 525)(-325 500);
WIRE 16 -1 (-325 675)(-325 625);
WIRE 16 -1 (-325 625)(-450 625);
WIRE 16 -1 (-325 725)(-325 675);
WIRE 16 -1 (-325 675)(-450 675);
WIRE 16 -1 (-325 775)(-325 725);
WIRE 16 -1 (-325 725)(-450 725);
WIRE 16 -1 (-325 825)(-325 775);
WIRE 16 -1 (-450 775)(-325 775);
WIRE 16 -1 (-450 825)(-325 825);
WIRE 16 -1 (-325 875)(-325 825);
WIRE 16 -1 (-325 925)(-325 875);
WIRE 16 -1 (-325 875)(-450 875);
WIRE 16 -1 (-325 975)(-325 925);
WIRE 16 -1 (-325 925)(-450 925);
WIRE 16 -1 (-325 1025)(-325 975);
WIRE 16 -1 (-325 975)(-450 975);
WIRE 16 -1 (-325 1075)(-325 1025);
WIRE 16 -1 (-325 1025)(-450 1025);
WIRE 16 -1 (-325 1125)(-325 1075);
WIRE 16 -1 (-325 1075)(-450 1075);
WIRE 16 -1 (-325 1175)(-325 1125);
WIRE 16 -1 (-325 1125)(-450 1125);
WIRE 16 -1 (-450 1175)(-325 1175);
WIRE 16 -1 (-325 1225)(-325 1175);
WIRE 16 -1 (-450 1225)(-325 1225);
WIRE 16 -1 (-325 1275)(-325 1225);
WIRE 16 -1 (-325 1325)(-325 1275);
WIRE 16 -1 (-325 1275)(-450 1275);
WIRE 16 -1 (-325 1375)(-325 1325);
WIRE 16 -1 (-325 1325)(-450 1325);
WIRE 16 -1 (-325 1425)(-325 1375);
WIRE 16 -1 (-325 1375)(-450 1375);
WIRE 16 -1 (-325 1475)(-325 1425);
WIRE 16 -1 (-325 1425)(-450 1425);
WIRE 16 -1 (-325 1525)(-325 1475);
WIRE 16 -1 (-325 1475)(-450 1475);
WIRE 16 -1 (-325 1575)(-325 1525);
WIRE 16 -1 (-325 1525)(-450 1525);
WIRE 16 -1 (-325 1625)(-325 1575);
WIRE 16 -1 (-450 1575)(-325 1575);
WIRE 16 -1 (-450 1625)(-325 1625);
WIRE 16 -1 (-325 1675)(-325 1625);
WIRE 16 -1 (-325 1725)(-325 1675);
WIRE 16 -1 (-325 1675)(-450 1675);
WIRE 16 -1 (-325 1775)(-325 1725);
WIRE 16 -1 (-325 1725)(-450 1725);
WIRE 16 -1 (-325 1825)(-325 1775);
WIRE 16 -1 (-325 1775)(-450 1775);
WIRE 16 -1 (-325 1875)(-325 1825);
WIRE 16 -1 (-325 1825)(-450 1825);
WIRE 16 -1 (-325 1925)(-325 1875);
WIRE 16 -1 (-325 1875)(-450 1875);
WIRE 16 -1 (-325 1975)(-325 1925);
WIRE 16 -1 (-325 1925)(-450 1925);
WIRE 16 -1 (-450 1975)(-325 1975);
WIRE 16 -1 (-325 2025)(-325 1975);
WIRE 16 -1 (-450 2025)(-325 2025);
WIRE 16 -1 (-325 2075)(-325 2025);
WIRE 16 -1 (-325 2125)(-325 2075);
WIRE 16 -1 (-325 2075)(-450 2075);
WIRE 16 -1 (-325 2175)(-325 2125);
WIRE 16 -1 (-325 2125)(-450 2125);
WIRE 16 -1 (-325 2225)(-325 2175);
WIRE 16 -1 (-325 2175)(-450 2175);
WIRE 16 -1 (-325 2275)(-325 2225);
WIRE 16 -1 (-325 2225)(-450 2225);
WIRE 16 -1 (-325 2325)(-325 2275);
WIRE 16 -1 (-325 2275)(-450 2275);
WIRE 16 -1 (-325 2375)(-325 2325);
WIRE 16 -1 (-325 2325)(-450 2325);
WIRE 16 -1 (-450 2375)(-325 2375);
WIRE 16 -1 (-325 2425)(-325 2375);
WIRE 16 -1 (-450 2425)(-325 2425);
WIRE 16 -1 (-325 2475)(-325 2425);
WIRE 16 -1 (-325 2525)(-325 2475);
WIRE 16 -1 (-325 2475)(-450 2475);
WIRE 16 -1 (-325 2575)(-325 2525);
WIRE 16 -1 (-325 2525)(-450 2525);
WIRE 16 -1 (-325 2625)(-325 2575);
WIRE 16 -1 (-325 2575)(-450 2575);
WIRE 16 -1 (-325 2675)(-325 2625);
WIRE 16 -1 (-325 2625)(-450 2625);
WIRE 16 -1 (-325 2725)(-325 2675);
WIRE 16 -1 (-325 2675)(-450 2675);
WIRE 16 -1 (-325 2775)(-325 2725);
WIRE 16 -1 (-325 2725)(-450 2725);
WIRE 16 -1 (-450 2775)(-325 2775);
WIRE 16 -1 (-325 2825)(-325 2775);
WIRE 16 -1 (-325 2875)(-325 2825);
WIRE 16 -1 (-450 2825)(-325 2825);
WIRE 16 -1 (-325 2925)(-325 2875);
WIRE 16 -1 (-325 2875)(-450 2875);
WIRE 16 -1 (-325 2975)(-325 2925);
WIRE 16 -1 (-325 2925)(-450 2925);
WIRE 16 -1 (-325 3025)(-325 2975);
WIRE 16 -1 (-325 2975)(-450 2975);
WIRE 16 -1 (-325 3075)(-325 3025);
WIRE 16 -1 (-325 3025)(-450 3025);
WIRE 16 -1 (-325 3125)(-325 3075);
WIRE 16 -1 (-325 3075)(-450 3075);
WIRE 16 -1 (-325 3175)(-325 3125);
WIRE 16 -1 (-325 3125)(-450 3125);
WIRE 16 -1 (-450 3175)(-325 3175);
WIRE 16 -1 (-325 3225)(-325 3175);
WIRE 16 -1 (-450 3225)(-325 3225);
WIRE 16 -1 (-325 3275)(-325 3225);
WIRE 16 -1 (-325 3325)(-325 3275);
WIRE 16 -1 (-325 3275)(-450 3275);
WIRE 16 -1 (-325 3375)(-325 3325);
WIRE 16 -1 (-325 3325)(-450 3325);
WIRE 16 -1 (-325 3425)(-325 3375);
WIRE 16 -1 (-325 3375)(-450 3375);
WIRE 16 -1 (-325 3475)(-325 3425);
WIRE 16 -1 (-325 3425)(-450 3425);
WIRE 16 -1 (-325 3525)(-325 3475);
WIRE 16 -1 (-325 3475)(-450 3475);
WIRE 16 -1 (-325 3575)(-325 3525);
WIRE 16 -1 (-325 3525)(-450 3525);
WIRE 16 -1 (-450 3575)(-325 3575);
WIRE 16 -1 (-325 3625)(-325 3575);
WIRE 16 -1 (-325 3675)(-325 3625);
WIRE 16 -1 (-450 3625)(-325 3625);
WIRE 16 -1 (-325 3725)(-325 3675);
WIRE 16 -1 (-325 3675)(-450 3675);
WIRE 16 -1 (-325 3775)(-325 3725);
WIRE 16 -1 (-325 3725)(-450 3725);
WIRE 16 -1 (-325 3825)(-325 3775);
WIRE 16 -1 (-325 3775)(-450 3775);
WIRE 16 -1 (-325 3875)(-325 3825);
WIRE 16 -1 (-325 3825)(-450 3825);
WIRE 16 -1 (-325 3925)(-325 3875);
WIRE 16 -1 (-325 3875)(-450 3875);
WIRE 16 -1 (-325 3975)(-325 3925);
WIRE 16 -1 (-325 3925)(-450 3925);
WIRE 16 -1 (-450 3975)(-325 3975);
WIRE 16 -1 (-325 4025)(-325 3975);
WIRE 16 -1 (-450 4025)(-325 4025);
WIRE 16 -1 (-325 4075)(-325 4025);
WIRE 16 -1 (-325 4125)(-325 4075);
WIRE 16 -1 (-325 4075)(-450 4075);
WIRE 16 -1 (-325 4175)(-325 4125);
WIRE 16 -1 (-325 4125)(-450 4125);
WIRE 16 -1 (-325 4225)(-325 4175);
WIRE 16 -1 (-325 4175)(-450 4175);
WIRE 16 -1 (-325 4275)(-325 4225);
WIRE 16 -1 (-325 4225)(-450 4225);
WIRE 16 -1 (-325 4325)(-325 4275);
WIRE 16 -1 (-325 4275)(-450 4275);
WIRE 16 -1 (-325 4375)(-325 4325);
WIRE 16 -1 (-325 4325)(-450 4325);
WIRE 16 -1 (-325 4425)(-325 4375);
WIRE 16 -1 (-450 4375)(-325 4375);
WIRE 16 -1 (-450 4425)(-325 4425);
WIRE 16 -1 (-325 4475)(-325 4425);
WIRE 16 -1 (-325 4525)(-325 4475);
WIRE 16 -1 (-325 4475)(-450 4475);
WIRE 16 -1 (-325 4575)(-325 4525);
WIRE 16 -1 (-325 4525)(-450 4525);
WIRE 16 -1 (-325 4625)(-325 4575);
WIRE 16 -1 (-325 4575)(-450 4575);
WIRE 16 -1 (-325 4675)(-325 4625);
WIRE 16 -1 (-325 4625)(-450 4625);
WIRE 16 -1 (-325 4725)(-325 4675);
WIRE 16 -1 (-325 4675)(-450 4675);
WIRE 16 -1 (-325 4775)(-325 4725);
WIRE 16 -1 (-325 4725)(-450 4725);
WIRE 16 -1 (-450 4775)(-325 4775);
WIRE 16 -1 (-325 4825)(-325 4775);
WIRE 16 -1 (-450 4825)(-325 4825);
WIRE 16 -1 (-325 4875)(-325 4825);
WIRE 16 -1 (-325 4925)(-325 4875);
WIRE 16 -1 (-325 4875)(-450 4875);
WIRE 16 -1 (-325 4975)(-325 4925);
WIRE 16 -1 (-325 4925)(-450 4925);
WIRE 16 -1 (-325 5025)(-325 4975);
WIRE 16 -1 (-325 4975)(-450 4975);
WIRE 16 -1 (-325 5075)(-325 5025);
WIRE 16 -1 (-325 5025)(-450 5025);
WIRE 16 -1 (-325 5125)(-325 5075);
WIRE 16 -1 (-325 5075)(-450 5075);
WIRE 16 -1 (-325 5175)(-325 5125);
WIRE 16 -1 (-325 5125)(-450 5125);
WIRE 16 -1 (-450 5175)(-325 5175);
WIRE 16 -1 (-325 5225)(-325 5175);
WIRE 16 -1 (-450 5225)(-325 5225);
WIRE 16 -1 (-325 5275)(-325 5225);
WIRE 16 -1 (-325 5325)(-325 5275);
WIRE 16 -1 (-325 5275)(-450 5275);
WIRE 16 -1 (-325 5375)(-325 5325);
WIRE 16 -1 (-325 5325)(-450 5325);
WIRE 16 -1 (-325 5425)(-325 5375);
WIRE 16 -1 (-325 5375)(-450 5375);
WIRE 16 -1 (-325 5475)(-325 5425);
WIRE 16 -1 (-325 5425)(-450 5425);
WIRE 16 -1 (-325 5525)(-325 5475);
WIRE 16 -1 (-325 5475)(-450 5475);
WIRE 16 -1 (-325 5575)(-325 5525);
WIRE 16 -1 (-325 5525)(-450 5525);
WIRE 16 -1 (-450 5575)(-325 5575);
WIRE 16 -1 (-325 5625)(-325 5575);
WIRE 16 -1 (-450 5625)(-325 5625);
WIRE 16 -1 (-325 5675)(-325 5625);
WIRE 16 -1 (-325 5725)(-325 5675);
WIRE 16 -1 (-325 5675)(-450 5675);
WIRE 16 -1 (-325 5775)(-325 5725);
WIRE 16 -1 (-325 5725)(-450 5725);
WIRE 16 -1 (-325 5825)(-325 5775);
WIRE 16 -1 (-325 5775)(-450 5775);
WIRE 16 -1 (-325 5875)(-325 5825);
WIRE 16 -1 (-325 5825)(-450 5825);
WIRE 16 -1 (-325 5925)(-325 5875);
WIRE 16 -1 (-325 5875)(-450 5875);
WIRE 16 -1 (-325 5975)(-325 5925);
WIRE 16 -1 (-325 5925)(-450 5925);
WIRE 16 -1 (-450 5975)(-325 5975);
WIRE 16 -1 (-325 6025)(-325 5975);
WIRE 16 -1 (-450 6025)(-325 6025);
WIRE 16 -1 (-325 6075)(-325 6025);
WIRE 16 -1 (-450 6075)(-325 6075);
WIRE 16 -1 (-325 6125)(-325 6075);
WIRE 16 -1 (-450 6125)(-325 6125);
WIRE 16 -1 (-325 6175)(-325 6125);
WIRE 16 -1 (-325 6225)(-325 6175);
WIRE 16 -1 (-450 6175)(-325 6175);
WIRE 16 -1 (-450 6225)(-325 6225);
WIRE 16 -1 (-325 6275)(-325 6225);
WIRE 16 -1 (-450 6275)(-325 6275);
WIRE 16 -1 (-325 6325)(-325 6275);
WIRE 16 -1 (-450 6325)(-325 6325);
WIRE 16 -1 (-325 6375)(-325 6325);
WIRE 16 -1 (-325 6425)(-325 6375);
WIRE 16 -1 (-325 6375)(-450 6375);
WIRE 16 -1 (-325 6425)(-450 6425);
DOT 1 (-9275 3100);
DOT 1 (-9275 3150);
DOT 1 (-9275 450);
DOT 1 (-9275 500);
DOT 1 (-9275 600);
DOT 1 (-9275 550);
DOT 1 (-9275 750);
DOT 1 (-9275 700);
DOT 1 (-9275 800);
DOT 1 (-9275 850);
DOT 1 (-9275 900);
DOT 1 (-9275 1000);
DOT 1 (-9275 950);
DOT 1 (-9275 1150);
DOT 1 (-9275 1100);
DOT 1 (-9275 1050);
DOT 1 (-9275 1200);
DOT 1 (-9275 1250);
DOT 1 (-9275 1400);
DOT 1 (-9275 1350);
DOT 1 (-9275 1300);
DOT 1 (-9275 1500);
DOT 1 (-9275 1450);
DOT 1 (-9275 1650);
DOT 1 (-9275 1600);
DOT 1 (-9275 1550);
DOT 1 (-9275 1700);
DOT 1 (-9275 1750);
DOT 1 (-9275 1800);
DOT 1 (-9275 1900);
DOT 1 (-9275 1850);
DOT 1 (-9275 1950);
DOT 1 (-9275 2000);
DOT 1 (-9275 2050);
DOT 1 (-9275 2150);
DOT 1 (-9275 2100);
DOT 1 (-9275 2300);
DOT 1 (-9275 2250);
DOT 1 (-9275 2200);
DOT 1 (-9275 2350);
DOT 1 (-9275 2400);
DOT 1 (-9275 2550);
DOT 1 (-9275 2500);
DOT 1 (-9275 2450);
DOT 1 (-9275 2650);
DOT 1 (-9275 2600);
DOT 1 (-9275 2700);
DOT 1 (-9275 2800);
DOT 1 (-9275 2750);
DOT 1 (-9275 2850);
DOT 1 (-9275 2900);
DOT 1 (-9275 2950);
DOT 1 (-9275 3050);
DOT 1 (-9275 3000);
DOT 1 (-9275 3200);
DOT 1 (-9275 3250);
DOT 1 (-9275 3300);
DOT 1 (-9275 3450);
DOT 1 (-9275 3400);
DOT 1 (-9275 3350);
DOT 1 (-9275 3550);
DOT 1 (-9275 3500);
DOT 1 (-9275 3700);
DOT 1 (-9275 3650);
DOT 1 (-9275 3600);
DOT 1 (-9275 3750);
DOT 1 (-9275 3800);
DOT 1 (-9275 3850);
DOT 1 (-9275 3950);
DOT 1 (-9275 3900);
DOT 1 (-9275 4050);
DOT 1 (-9275 4000);
DOT 1 (-9275 4100);
DOT 1 (-9275 4200);
DOT 1 (-9275 4150);
DOT 1 (-9275 4350);
DOT 1 (-9275 4300);
DOT 1 (-9275 4250);
DOT 1 (-9275 4400);
DOT 1 (-9275 4450);
DOT 1 (-9275 4600);
DOT 1 (-9275 4550);
DOT 1 (-9275 4500);
DOT 1 (-9275 4700);
DOT 1 (-9275 4650);
DOT 1 (-9275 4850);
DOT 1 (-9275 4800);
DOT 1 (-9275 4750);
DOT 1 (-9275 4900);
DOT 1 (-9275 4950);
DOT 1 (-9275 5000);
DOT 1 (-9275 5100);
DOT 1 (-9275 5050);
DOT 1 (-9275 5200);
DOT 1 (-9275 5150);
DOT 1 (-9275 5250);
DOT 1 (-9275 5350);
DOT 1 (-9275 5300);
DOT 1 (-9275 5450);
DOT 1 (-9275 5400);
DOT 1 (-9275 5600);
DOT 1 (-9275 5550);
DOT 1 (-9275 5750);
DOT 1 (-9275 5700);
DOT 1 (-9275 5650);
DOT 1 (-9275 5800);
DOT 1 (-9275 5850);
DOT 1 (-9275 5900);
DOT 1 (-9275 6000);
DOT 1 (-9275 5950);
DOT 1 (-9275 6050);
DOT 1 (-9275 6100);
DOT 1 (-9275 6150);
DOT 1 (-9275 6200);
DOT 1 (-9275 6250);
DOT 1 (-9275 6300);
DOT 1 (-9275 650);
DOT 1 (-7925 450);
DOT 1 (-7925 500);
DOT 1 (-7925 950);
DOT 1 (-7925 1000);
DOT 1 (-7925 900);
DOT 1 (-7925 850);
DOT 1 (-7925 800);
DOT 1 (-7925 700);
DOT 1 (-7925 750);
DOT 1 (-7925 650);
DOT 1 (-7925 550);
DOT 1 (-7925 600);
DOT 1 (-7925 1300);
DOT 1 (-7925 1100);
DOT 1 (-7925 1500);
DOT 1 (-7925 1450);
DOT 1 (-7925 1400);
DOT 1 (-7925 1350);
DOT 1 (-7925 1250);
DOT 1 (-7925 1200);
DOT 1 (-7925 1150);
DOT 1 (-7925 1050);
DOT 1 (-7925 2000);
DOT 1 (-7925 1950);
DOT 1 (-7925 1850);
DOT 1 (-7925 1900);
DOT 1 (-7925 1800);
DOT 1 (-7925 1750);
DOT 1 (-7925 1700);
DOT 1 (-7925 1650);
DOT 1 (-7925 1550);
DOT 1 (-7925 1600);
DOT 1 (-7925 2050);
DOT 1 (-7925 2550);
DOT 1 (-7925 2450);
DOT 1 (-7925 2500);
DOT 1 (-7925 2400);
DOT 1 (-7925 2350);
DOT 1 (-7925 2300);
DOT 1 (-7925 2200);
DOT 1 (-7925 2250);
DOT 1 (-7925 2100);
DOT 1 (-7925 2150);
DOT 1 (-7925 3000);
DOT 1 (-7925 3050);
DOT 1 (-7925 2950);
DOT 1 (-7925 2900);
DOT 1 (-7925 2850);
DOT 1 (-7925 2750);
DOT 1 (-7925 2800);
DOT 1 (-7925 2700);
DOT 1 (-7925 2650);
DOT 1 (-7925 2600);
DOT 1 (-7925 3550);
DOT 1 (-7925 3500);
DOT 1 (-7925 3450);
DOT 1 (-7925 3350);
DOT 1 (-7925 3400);
DOT 1 (-7925 3300);
DOT 1 (-7925 3250);
DOT 1 (-7925 3200);
DOT 1 (-7925 3150);
DOT 1 (-7925 3100);
DOT 1 (-7925 4050);
DOT 1 (-7925 4000);
DOT 1 (-7925 3900);
DOT 1 (-7925 3950);
DOT 1 (-7925 3850);
DOT 1 (-7925 3800);
DOT 1 (-7925 3750);
DOT 1 (-7925 3700);
DOT 1 (-7925 3600);
DOT 1 (-7925 3650);
DOT 1 (-7925 4100);
DOT 1 (-7925 4600);
DOT 1 (-7925 4500);
DOT 1 (-7925 4550);
DOT 1 (-7925 4450);
DOT 1 (-7925 4400);
DOT 1 (-7925 4350);
DOT 1 (-7925 4250);
DOT 1 (-7925 4300);
DOT 1 (-7925 4150);
DOT 1 (-7925 4200);
DOT 1 (-7925 5050);
DOT 1 (-7925 5100);
DOT 1 (-7925 5000);
DOT 1 (-7925 4950);
DOT 1 (-7925 4900);
DOT 1 (-7925 4850);
DOT 1 (-7925 4750);
DOT 1 (-7925 4800);
DOT 1 (-7925 4700);
DOT 1 (-7925 4650);
DOT 1 (-7925 5600);
DOT 1 (-7925 5550);
DOT 1 (-7925 5500);
DOT 1 (-7925 5400);
DOT 1 (-7925 5450);
DOT 1 (-7925 5300);
DOT 1 (-7925 5350);
DOT 1 (-7925 5250);
DOT 1 (-7925 5200);
DOT 1 (-7925 5150);
DOT 1 (-7925 6100);
DOT 1 (-7925 6050);
DOT 1 (-7925 5950);
DOT 1 (-7925 5900);
DOT 1 (-7925 5800);
DOT 1 (-7925 5750);
DOT 1 (-7925 5650);
DOT 1 (-7925 5700);
DOT 1 (-7925 5850);
DOT 1 (-7925 6150);
DOT 1 (-7925 6300);
DOT 1 (-7925 6200);
DOT 1 (-7925 6250);
DOT 1 (-7925 6000);
DOT 1 (-9275 5500);
DOT 1 (-7750 475);
DOT 1 (-7750 525);
DOT 1 (-7750 575);
DOT 1 (-7750 625);
DOT 1 (-7750 725);
DOT 1 (-7750 675);
DOT 1 (-7750 775);
DOT 1 (-7750 825);
DOT 1 (-7750 875);
DOT 1 (-7750 975);
DOT 1 (-7750 925);
DOT 1 (-7750 1025);
DOT 1 (-7750 1075);
DOT 1 (-7750 1125);
DOT 1 (-7750 1175);
DOT 1 (-7750 1225);
DOT 1 (-7750 1275);
DOT 1 (-7750 1375);
DOT 1 (-7750 1325);
DOT 1 (-7750 1425);
DOT 1 (-7750 1475);
DOT 1 (-7750 1525);
DOT 1 (-7750 1625);
DOT 1 (-7750 1575);
DOT 1 (-7750 1675);
DOT 1 (-7750 1725);
DOT 1 (-7750 1775);
DOT 1 (-7750 1875);
DOT 1 (-7750 1825);
DOT 1 (-7750 1925);
DOT 1 (-7750 1975);
DOT 1 (-7750 2025);
DOT 1 (-6400 475);
DOT 1 (-6400 525);
DOT 1 (-6400 625);
DOT 1 (-6400 575);
DOT 1 (-6400 675);
DOT 1 (-6400 725);
DOT 1 (-6400 775);
DOT 1 (-6400 825);
DOT 1 (-6400 875);
DOT 1 (-6400 925);
DOT 1 (-6400 975);
DOT 1 (-6400 1025);
DOT 1 (-6400 1075);
DOT 1 (-6400 1125);
DOT 1 (-6400 1175);
DOT 1 (-6400 1225);
DOT 1 (-6400 1275);
DOT 1 (-6400 1375);
DOT 1 (-6400 1325);
DOT 1 (-6400 1425);
DOT 1 (-6400 1475);
DOT 1 (-6400 1525);
DOT 1 (-6400 1625);
DOT 1 (-6400 1575);
DOT 1 (-6400 1675);
DOT 1 (-6400 1725);
DOT 1 (-6400 1775);
DOT 1 (-6400 1825);
DOT 1 (-6400 1875);
DOT 1 (-6400 1925);
DOT 1 (-6400 1975);
DOT 1 (-6400 2025);
DOT 1 (-7750 2075);
DOT 1 (-7750 2125);
DOT 1 (-7750 2175);
DOT 1 (-7750 2275);
DOT 1 (-7750 2225);
DOT 1 (-7750 2325);
DOT 1 (-7750 2375);
DOT 1 (-7750 2425);
DOT 1 (-7750 2525);
DOT 1 (-7750 2475);
DOT 1 (-7750 2575);
DOT 1 (-7750 2625);
DOT 1 (-7750 2675);
DOT 1 (-7750 2775);
DOT 1 (-7750 2725);
DOT 1 (-7750 2825);
DOT 1 (-7750 2875);
DOT 1 (-7750 2925);
DOT 1 (-7750 3025);
DOT 1 (-7750 2975);
DOT 1 (-7750 3075);
DOT 1 (-7750 3125);
DOT 1 (-7750 3175);
DOT 1 (-7750 3225);
DOT 1 (-7750 3275);
DOT 1 (-7750 3325);
DOT 1 (-7750 3425);
DOT 1 (-7750 3375);
DOT 1 (-7750 3475);
DOT 1 (-7750 3525);
DOT 1 (-7750 3575);
DOT 1 (-7750 3675);
DOT 1 (-7750 3625);
DOT 1 (-7750 3725);
DOT 1 (-7750 3775);
DOT 1 (-7750 3825);
DOT 1 (-7750 3925);
DOT 1 (-7750 3875);
DOT 1 (-7750 3975);
DOT 1 (-7750 4025);
DOT 1 (-7750 4075);
DOT 1 (-6400 2175);
DOT 1 (-6400 2125);
DOT 1 (-6400 2075);
DOT 1 (-6400 2275);
DOT 1 (-6400 2225);
DOT 1 (-6400 2325);
DOT 1 (-6400 2375);
DOT 1 (-6400 2425);
DOT 1 (-6400 2525);
DOT 1 (-6400 2475);
DOT 1 (-6400 2625);
DOT 1 (-6400 2675);
DOT 1 (-6400 2575);
DOT 1 (-6400 2725);
DOT 1 (-6400 2775);
DOT 1 (-6400 2825);
DOT 1 (-6400 2875);
DOT 1 (-6400 2925);
DOT 1 (-6400 2975);
DOT 1 (-6400 3025);
DOT 1 (-6400 3075);
DOT 1 (-6400 3125);
DOT 1 (-6400 3175);
DOT 1 (-6400 3225);
DOT 1 (-6400 3275);
DOT 1 (-6400 3325);
DOT 1 (-6400 3375);
DOT 1 (-6400 3425);
DOT 1 (-6400 3475);
DOT 1 (-6400 3525);
DOT 1 (-6400 3575);
DOT 1 (-6400 3675);
DOT 1 (-6400 3625);
DOT 1 (-6400 3725);
DOT 1 (-6400 3775);
DOT 1 (-6400 3825);
DOT 1 (-6400 3875);
DOT 1 (-6400 3925);
DOT 1 (-6400 3975);
DOT 1 (-6400 4025);
DOT 1 (-6400 4075);
DOT 1 (-7750 4175);
DOT 1 (-7750 4125);
DOT 1 (-7750 4225);
DOT 1 (-7750 4275);
DOT 1 (-7750 4325);
DOT 1 (-7750 4375);
DOT 1 (-7750 4475);
DOT 1 (-7750 4575);
DOT 1 (-7750 4525);
DOT 1 (-7750 4625);
DOT 1 (-7750 4675);
DOT 1 (-7750 4725);
DOT 1 (-7750 4825);
DOT 1 (-7750 4775);
DOT 1 (-7750 4875);
DOT 1 (-7750 4925);
DOT 1 (-7750 4975);
DOT 1 (-7750 5025);
DOT 1 (-7750 5075);
DOT 1 (-7750 5125);
DOT 1 (-7750 5175);
DOT 1 (-7750 5225);
DOT 1 (-7750 5275);
DOT 1 (-7750 5325);
DOT 1 (-7750 5375);
DOT 1 (-7750 5475);
DOT 1 (-7750 5525);
DOT 1 (-7750 5575);
DOT 1 (-7750 5625);
DOT 1 (-7750 5725);
DOT 1 (-7750 5675);
DOT 1 (-7750 5775);
DOT 1 (-7750 5825);
DOT 1 (-7750 5875);
DOT 1 (-7750 5925);
DOT 1 (-7750 5975);
DOT 1 (-7750 6025);
DOT 1 (-7750 6125);
DOT 1 (-7750 6075);
DOT 1 (-6400 4175);
DOT 1 (-6400 4125);
DOT 1 (-6400 4225);
DOT 1 (-6400 4325);
DOT 1 (-6400 4275);
DOT 1 (-6400 4375);
DOT 1 (-6400 4425);
DOT 1 (-6400 4475);
DOT 1 (-6400 4575);
DOT 1 (-6400 4525);
DOT 1 (-6400 4675);
DOT 1 (-6400 4725);
DOT 1 (-6400 4625);
DOT 1 (-6400 4825);
DOT 1 (-6400 4775);
DOT 1 (-6400 4875);
DOT 1 (-6400 4925);
DOT 1 (-6400 4975);
DOT 1 (-6400 5025);
DOT 1 (-6400 5075);
DOT 1 (-6400 5125);
DOT 1 (-6400 5175);
DOT 1 (-6400 5225);
DOT 1 (-6400 5275);
DOT 1 (-6400 5375);
DOT 1 (-6400 5325);
DOT 1 (-6400 5475);
DOT 1 (-6400 5425);
DOT 1 (-6400 5525);
DOT 1 (-6400 5575);
DOT 1 (-6400 5625);
DOT 1 (-6400 5725);
DOT 1 (-6400 5675);
DOT 1 (-6400 5775);
DOT 1 (-6400 5825);
DOT 1 (-6400 5875);
DOT 1 (-6400 5925);
DOT 1 (-6400 5975);
DOT 1 (-6400 6025);
DOT 1 (-6400 6075);
DOT 1 (-6400 6125);
DOT 1 (-7750 6175);
DOT 1 (-7750 6225);
DOT 1 (-6400 6225);
DOT 1 (-6400 6175);
DOT 1 (-7750 5425);
DOT 1 (-7750 4425);
DOT 1 (-6275 500);
DOT 1 (-6275 600);
DOT 1 (-6275 550);
DOT 1 (-6275 650);
DOT 1 (-6275 750);
DOT 1 (-6275 700);
DOT 1 (-6275 850);
DOT 1 (-6275 800);
DOT 1 (-6275 900);
DOT 1 (-6275 1000);
DOT 1 (-6275 950);
DOT 1 (-6275 1150);
DOT 1 (-6275 1100);
DOT 1 (-6275 1050);
DOT 1 (-6275 1250);
DOT 1 (-6275 1200);
DOT 1 (-6275 1400);
DOT 1 (-6275 1350);
DOT 1 (-6275 1300);
DOT 1 (-6275 1500);
DOT 1 (-6275 1450);
DOT 1 (-6275 1550);
DOT 1 (-6275 1600);
DOT 1 (-6275 1650);
DOT 1 (-6275 1750);
DOT 1 (-6275 1700);
DOT 1 (-6275 1800);
DOT 1 (-6275 1900);
DOT 1 (-6275 1850);
DOT 1 (-6275 2000);
DOT 1 (-6275 1950);
DOT 1 (-6275 2050);
DOT 1 (-6275 2150);
DOT 1 (-6275 2100);
DOT 1 (-6275 2300);
DOT 1 (-6275 2250);
DOT 1 (-6275 2200);
DOT 1 (-6275 2400);
DOT 1 (-6275 2350);
DOT 1 (-6275 2550);
DOT 1 (-6275 2500);
DOT 1 (-6275 2450);
DOT 1 (-6275 2650);
DOT 1 (-6275 2600);
DOT 1 (-6275 2700);
DOT 1 (-6275 2800);
DOT 1 (-6275 2750);
DOT 1 (-6275 2900);
DOT 1 (-6275 2850);
DOT 1 (-6275 2950);
DOT 1 (-6275 3050);
DOT 1 (-6275 3000);
DOT 1 (-6275 3150);
DOT 1 (-6275 3100);
DOT 1 (-6275 3200);
DOT 1 (-6275 3300);
DOT 1 (-6275 3250);
DOT 1 (-6275 3450);
DOT 1 (-6275 3400);
DOT 1 (-6275 3350);
DOT 1 (-6275 3550);
DOT 1 (-6275 3500);
DOT 1 (-6275 3700);
DOT 1 (-6275 3650);
DOT 1 (-6275 3600);
DOT 1 (-6275 3800);
DOT 1 (-6275 3750);
DOT 1 (-6275 3850);
DOT 1 (-6275 3950);
DOT 1 (-6275 3900);
DOT 1 (-6275 4000);
DOT 1 (-4925 550);
DOT 1 (-4925 600);
DOT 1 (-4925 650);
DOT 1 (-4925 700);
DOT 1 (-4925 750);
DOT 1 (-4925 850);
DOT 1 (-4925 800);
DOT 1 (-4925 900);
DOT 1 (-4925 1000);
DOT 1 (-4925 950);
DOT 1 (-4925 1150);
DOT 1 (-4925 1050);
DOT 1 (-4925 1100);
DOT 1 (-4925 1250);
DOT 1 (-4925 1200);
DOT 1 (-4925 1300);
DOT 1 (-4925 1350);
DOT 1 (-4925 1400);
DOT 1 (-4925 1450);
DOT 1 (-4925 1500);
DOT 1 (-4925 1650);
DOT 1 (-4925 1600);
DOT 1 (-4925 1550);
DOT 1 (-4925 1750);
DOT 1 (-4925 1700);
DOT 1 (-4925 1800);
DOT 1 (-4925 1850);
DOT 1 (-4925 1900);
DOT 1 (-4925 2000);
DOT 1 (-4925 1950);
DOT 1 (-4925 2050);
DOT 1 (-4925 2100);
DOT 1 (-4925 2150);
DOT 1 (-4925 2250);
DOT 1 (-4925 2200);
DOT 1 (-4925 2300);
DOT 1 (-4925 2400);
DOT 1 (-4925 2350);
DOT 1 (-4925 2550);
DOT 1 (-4925 2500);
DOT 1 (-4925 2450);
DOT 1 (-4925 2600);
DOT 1 (-4925 2650);
DOT 1 (-4925 2700);
DOT 1 (-4925 2800);
DOT 1 (-4925 2750);
DOT 1 (-4925 2850);
DOT 1 (-4925 2900);
DOT 1 (-4925 2950);
DOT 1 (-4925 3050);
DOT 1 (-4925 3000);
DOT 1 (-4925 3150);
DOT 1 (-4925 3100);
DOT 1 (-4925 3200);
DOT 1 (-4925 3250);
DOT 1 (-4925 3300);
DOT 1 (-4925 3350);
DOT 1 (-4925 3400);
DOT 1 (-4925 3450);
DOT 1 (-4925 3500);
DOT 1 (-4925 3550);
DOT 1 (-4925 3650);
DOT 1 (-4925 3600);
DOT 1 (-4925 3700);
DOT 1 (-4925 3800);
DOT 1 (-4925 3750);
DOT 1 (-4925 3850);
DOT 1 (-4925 3900);
DOT 1 (-4925 3950);
DOT 1 (-4925 4050);
DOT 1 (-4925 4000);
DOT 1 (-6275 4100);
DOT 1 (-4925 4100);
DOT 1 (-6275 4150);
DOT 1 (-6275 4200);
DOT 1 (-6275 4300);
DOT 1 (-6275 4350);
DOT 1 (-6275 4250);
DOT 1 (-6275 4450);
DOT 1 (-6275 4400);
DOT 1 (-6275 4550);
DOT 1 (-6275 4600);
DOT 1 (-6275 4500);
DOT 1 (-6275 4700);
DOT 1 (-6275 4650);
DOT 1 (-6275 4750);
DOT 1 (-6275 4800);
DOT 1 (-6275 4850);
DOT 1 (-6275 4900);
DOT 1 (-6275 4950);
DOT 1 (-6275 5000);
DOT 1 (-6275 5050);
DOT 1 (-6275 5100);
DOT 1 (-6275 5150);
DOT 1 (-6275 5200);
DOT 1 (-6275 5250);
DOT 1 (-6275 5350);
DOT 1 (-6275 5300);
DOT 1 (-6275 5500);
DOT 1 (-6275 5450);
DOT 1 (-6275 5400);
DOT 1 (-6275 5600);
DOT 1 (-6275 5550);
DOT 1 (-6275 5750);
DOT 1 (-6275 5700);
DOT 1 (-6275 5650);
DOT 1 (-6275 5850);
DOT 1 (-6275 5800);
DOT 1 (-6275 5900);
DOT 1 (-6275 6000);
DOT 1 (-6275 5950);
DOT 1 (-6275 6100);
DOT 1 (-6275 6050);
DOT 1 (-6275 6150);
DOT 1 (-6275 6250);
DOT 1 (-6275 6200);
DOT 1 (-4925 4150);
DOT 1 (-4925 4200);
DOT 1 (-4925 4300);
DOT 1 (-4925 4250);
DOT 1 (-4925 4350);
DOT 1 (-4925 4450);
DOT 1 (-4925 4400);
DOT 1 (-4925 4600);
DOT 1 (-4925 4550);
DOT 1 (-4925 4500);
DOT 1 (-4925 4650);
DOT 1 (-4925 4700);
DOT 1 (-4925 4750);
DOT 1 (-4925 4800);
DOT 1 (-4925 4850);
DOT 1 (-4925 4950);
DOT 1 (-4925 4900);
DOT 1 (-4925 5000);
DOT 1 (-4925 5100);
DOT 1 (-4925 5050);
DOT 1 (-4925 5200);
DOT 1 (-4925 5150);
DOT 1 (-4925 5250);
DOT 1 (-4925 5300);
DOT 1 (-4925 5350);
DOT 1 (-4925 5450);
DOT 1 (-4925 5400);
DOT 1 (-4925 5500);
DOT 1 (-4925 5550);
DOT 1 (-4925 5600);
DOT 1 (-4925 5700);
DOT 1 (-4925 5650);
DOT 1 (-4925 5750);
DOT 1 (-4925 5850);
DOT 1 (-4925 5800);
DOT 1 (-4925 5900);
DOT 1 (-4925 5950);
DOT 1 (-4925 6000);
DOT 1 (-4925 6100);
DOT 1 (-4925 6050);
DOT 1 (-4925 6150);
DOT 1 (-4925 6200);
DOT 1 (-4925 6250);
DOT 1 (-4775 575);
DOT 1 (-4775 625);
DOT 1 (-4775 725);
DOT 1 (-4775 675);
DOT 1 (-4775 775);
DOT 1 (-4775 825);
DOT 1 (-4775 875);
DOT 1 (-4775 925);
DOT 1 (-4775 975);
DOT 1 (-4775 1025);
DOT 1 (-4775 1075);
DOT 1 (-4775 1125);
DOT 1 (-4775 1175);
DOT 1 (-4775 1225);
DOT 1 (-4775 1275);
DOT 1 (-4775 1325);
DOT 1 (-4775 1375);
DOT 1 (-4775 1425);
DOT 1 (-4775 1475);
DOT 1 (-4775 1525);
DOT 1 (-4775 1575);
DOT 1 (-4775 1625);
DOT 1 (-4775 1675);
DOT 1 (-4775 1725);
DOT 1 (-4775 1775);
DOT 1 (-4775 1825);
DOT 1 (-4775 1875);
DOT 1 (-4775 1925);
DOT 1 (-4775 1975);
DOT 1 (-4775 2025);
DOT 1 (-4775 2075);
DOT 1 (-4775 2125);
DOT 1 (-4775 2175);
DOT 1 (-4775 2225);
DOT 1 (-4775 2275);
DOT 1 (-4775 2325);
DOT 1 (-4775 2375);
DOT 1 (-4775 2425);
DOT 1 (-4775 2475);
DOT 1 (-4775 2525);
DOT 1 (-4775 2575);
DOT 1 (-4775 2625);
DOT 1 (-4775 2675);
DOT 1 (-4775 2725);
DOT 1 (-4775 2775);
DOT 1 (-4775 2825);
DOT 1 (-4775 2875);
DOT 1 (-4775 2925);
DOT 1 (-4775 2975);
DOT 1 (-4775 3025);
DOT 1 (-4775 3075);
DOT 1 (-4775 3125);
DOT 1 (-4775 3175);
DOT 1 (-4775 3225);
DOT 1 (-4775 3275);
DOT 1 (-4775 3325);
DOT 1 (-4775 3375);
DOT 1 (-4775 3425);
DOT 1 (-4775 3475);
DOT 1 (-4775 3525);
DOT 1 (-4775 3575);
DOT 1 (-4775 3625);
DOT 1 (-4775 3675);
DOT 1 (-4775 3725);
DOT 1 (-4775 3775);
DOT 1 (-4775 3825);
DOT 1 (-4775 3875);
DOT 1 (-4775 3925);
DOT 1 (-4775 3975);
DOT 1 (-4775 4025);
DOT 1 (-4775 4075);
DOT 1 (-4775 4125);
DOT 1 (-4775 4175);
DOT 1 (-4775 4225);
DOT 1 (-4775 4275);
DOT 1 (-4775 4325);
DOT 1 (-4775 4375);
DOT 1 (-4775 4425);
DOT 1 (-4775 4475);
DOT 1 (-4775 4525);
DOT 1 (-4775 4575);
DOT 1 (-4775 4625);
DOT 1 (-4775 4675);
DOT 1 (-4775 4725);
DOT 1 (-4775 4775);
DOT 1 (-4775 4825);
DOT 1 (-4775 4875);
DOT 1 (-4775 4925);
DOT 1 (-4775 4975);
DOT 1 (-4775 5025);
DOT 1 (-4775 5075);
DOT 1 (-4775 5125);
DOT 1 (-4775 5175);
DOT 1 (-4775 5225);
DOT 1 (-4775 5275);
DOT 1 (-4775 5325);
DOT 1 (-4775 5375);
DOT 1 (-4775 5425);
DOT 1 (-4775 5475);
DOT 1 (-4775 5525);
DOT 1 (-4775 5575);
DOT 1 (-4775 5625);
DOT 1 (-4775 5675);
DOT 1 (-4775 5725);
DOT 1 (-4775 5775);
DOT 1 (-4775 5825);
DOT 1 (-4775 5875);
DOT 1 (-4775 5925);
DOT 1 (-4775 5975);
DOT 1 (-4775 6025);
DOT 1 (-4775 6075);
DOT 1 (-4775 6125);
DOT 1 (-4775 6175);
DOT 1 (-4775 6225);
DOT 1 (-4775 6275);
DOT 1 (-4775 6325);
DOT 1 (-3425 575);
DOT 1 (-3425 625);
DOT 1 (-3425 675);
DOT 1 (-3425 725);
DOT 1 (-3425 775);
DOT 1 (-3425 825);
DOT 1 (-3425 875);
DOT 1 (-3425 925);
DOT 1 (-3425 975);
DOT 1 (-3425 1025);
DOT 1 (-3425 1075);
DOT 1 (-3425 1125);
DOT 1 (-3425 1175);
DOT 1 (-3425 1225);
DOT 1 (-3425 1275);
DOT 1 (-3425 1375);
DOT 1 (-3425 1325);
DOT 1 (-3425 1425);
DOT 1 (-3425 1475);
DOT 1 (-3425 1525);
DOT 1 (-3425 1575);
DOT 1 (-3425 1625);
DOT 1 (-3425 1675);
DOT 1 (-3425 1725);
DOT 1 (-3425 1775);
DOT 1 (-3425 1875);
DOT 1 (-3425 1825);
DOT 1 (-3425 1925);
DOT 1 (-3425 1975);
DOT 1 (-3425 2025);
DOT 1 (-3425 2075);
DOT 1 (-3425 2125);
DOT 1 (-3425 2175);
DOT 1 (-3425 2225);
DOT 1 (-3425 2275);
DOT 1 (-3425 2325);
DOT 1 (-3425 2375);
DOT 1 (-3425 2425);
DOT 1 (-3425 2475);
DOT 1 (-3425 2525);
DOT 1 (-3425 2575);
DOT 1 (-3425 2625);
DOT 1 (-3425 2675);
DOT 1 (-3425 2775);
DOT 1 (-3425 2725);
DOT 1 (-3425 2825);
DOT 1 (-3425 2875);
DOT 1 (-3425 2925);
DOT 1 (-3425 2975);
DOT 1 (-3425 3025);
DOT 1 (-3425 3075);
DOT 1 (-3425 3125);
DOT 1 (-3425 3175);
DOT 1 (-3425 3225);
DOT 1 (-3425 3275);
DOT 1 (-3425 3325);
DOT 1 (-3425 3425);
DOT 1 (-3425 3375);
DOT 1 (-3425 3475);
DOT 1 (-3425 3525);
DOT 1 (-3425 3575);
DOT 1 (-3425 3625);
DOT 1 (-3425 3675);
DOT 1 (-3425 3775);
DOT 1 (-3425 3825);
DOT 1 (-3425 3925);
DOT 1 (-3425 3875);
DOT 1 (-3425 3975);
DOT 1 (-3425 4025);
DOT 1 (-3425 4075);
DOT 1 (-3425 4125);
DOT 1 (-3425 4175);
DOT 1 (-3425 4225);
DOT 1 (-3425 4275);
DOT 1 (-3425 4325);
DOT 1 (-3425 4375);
DOT 1 (-3425 4425);
DOT 1 (-3425 4475);
DOT 1 (-3425 4525);
DOT 1 (-3425 4575);
DOT 1 (-3425 4625);
DOT 1 (-3425 4675);
DOT 1 (-3425 4725);
DOT 1 (-3425 4825);
DOT 1 (-3425 4775);
DOT 1 (-3425 4875);
DOT 1 (-3425 4925);
DOT 1 (-3425 4975);
DOT 1 (-3425 5025);
DOT 1 (-3425 5075);
DOT 1 (-3425 5125);
DOT 1 (-3425 5175);
DOT 1 (-3425 5225);
DOT 1 (-3425 5275);
DOT 1 (-3425 5325);
DOT 1 (-3425 5375);
DOT 1 (-3425 5425);
DOT 1 (-3425 5475);
DOT 1 (-3425 5525);
DOT 1 (-3425 5575);
DOT 1 (-3425 5625);
DOT 1 (-3425 5675);
DOT 1 (-3425 5725);
DOT 1 (-3425 5775);
DOT 1 (-3425 5825);
DOT 1 (-3425 5875);
DOT 1 (-3425 5975);
DOT 1 (-3425 5925);
DOT 1 (-3425 6025);
DOT 1 (-3425 6075);
DOT 1 (-3425 6125);
DOT 1 (-3425 6175);
DOT 1 (-3425 6225);
DOT 1 (-3425 6275);
DOT 1 (-3425 6325);
DOT 1 (-6275 4050);
DOT 1 (-3425 3725);
DOT 1 (-3275 525);
DOT 1 (-3275 575);
DOT 1 (-3275 625);
DOT 1 (-3275 675);
DOT 1 (-3275 725);
DOT 1 (-3275 775);
DOT 1 (-3275 825);
DOT 1 (-3275 875);
DOT 1 (-3275 925);
DOT 1 (-3275 975);
DOT 1 (-3275 1025);
DOT 1 (-3275 1075);
DOT 1 (-3275 1125);
DOT 1 (-3275 1275);
DOT 1 (-3275 1225);
DOT 1 (-3275 1175);
DOT 1 (-3275 1325);
DOT 1 (-3275 1375);
DOT 1 (-3275 1525);
DOT 1 (-3275 1475);
DOT 1 (-3275 1425);
DOT 1 (-3275 1575);
DOT 1 (-3275 1625);
DOT 1 (-3275 1675);
DOT 1 (-3275 1775);
DOT 1 (-3275 1725);
DOT 1 (-3275 1825);
DOT 1 (-3275 1875);
DOT 1 (-3275 1925);
DOT 1 (-3275 2025);
DOT 1 (-3275 1975);
DOT 1 (-3275 2075);
DOT 1 (-3275 2125);
DOT 1 (-3275 2175);
DOT 1 (-3275 2225);
DOT 1 (-3275 2275);
DOT 1 (-3275 2325);
DOT 1 (-3275 2375);
DOT 1 (-3275 2425);
DOT 1 (-3275 2475);
DOT 1 (-3275 2525);
DOT 1 (-3275 2575);
DOT 1 (-3275 2625);
DOT 1 (-3275 2675);
DOT 1 (-3275 2725);
DOT 1 (-3275 2775);
DOT 1 (-3275 2825);
DOT 1 (-3275 2875);
DOT 1 (-3275 2925);
DOT 1 (-3275 2975);
DOT 1 (-3275 3025);
DOT 1 (-3275 3075);
DOT 1 (-3275 3125);
DOT 1 (-3275 3175);
DOT 1 (-3275 3325);
DOT 1 (-3275 3275);
DOT 1 (-3275 3225);
DOT 1 (-3275 3375);
DOT 1 (-3275 3425);
DOT 1 (-3275 3575);
DOT 1 (-3275 3525);
DOT 1 (-3275 3475);
DOT 1 (-3275 3625);
DOT 1 (-3275 3675);
DOT 1 (-3275 3725);
DOT 1 (-3275 3775);
DOT 1 (-3275 3875);
DOT 1 (-3275 3925);
DOT 1 (-3275 3975);
DOT 1 (-3275 4075);
DOT 1 (-3275 4025);
DOT 1 (-1950 575);
DOT 1 (-1950 675);
DOT 1 (-1950 775);
DOT 1 (-1950 875);
DOT 1 (-1950 975);
DOT 1 (-1950 1025);
DOT 1 (-1950 1075);
DOT 1 (-1950 1125);
DOT 1 (-1950 1175);
DOT 1 (-1950 1225);
DOT 1 (-1950 1275);
DOT 1 (-1950 1375);
DOT 1 (-1950 1325);
DOT 1 (-1950 1425);
DOT 1 (-1950 1475);
DOT 1 (-1950 1525);
DOT 1 (-1950 1575);
DOT 1 (-1950 1625);
DOT 1 (-1950 1675);
DOT 1 (-1950 1725);
DOT 1 (-1950 1775);
DOT 1 (-1950 1875);
DOT 1 (-1950 1825);
DOT 1 (-1950 1925);
DOT 1 (-1950 1975);
DOT 1 (-1950 2025);
DOT 1 (-1950 2075);
DOT 1 (-1950 2125);
DOT 1 (-1950 2175);
DOT 1 (-1950 2275);
DOT 1 (-1950 2225);
DOT 1 (-1950 2325);
DOT 1 (-1950 2375);
DOT 1 (-1950 2425);
DOT 1 (-1950 2525);
DOT 1 (-1950 2475);
DOT 1 (-1950 2575);
DOT 1 (-1950 2625);
DOT 1 (-1950 2675);
DOT 1 (-1950 2775);
DOT 1 (-1950 2725);
DOT 1 (-1950 2825);
DOT 1 (-1950 2875);
DOT 1 (-1950 2925);
DOT 1 (-1950 3025);
DOT 1 (-1950 2975);
DOT 1 (-1950 3075);
DOT 1 (-1950 3125);
DOT 1 (-1950 3175);
DOT 1 (-1950 3225);
DOT 1 (-1950 3275);
DOT 1 (-1950 3325);
DOT 1 (-1950 3425);
DOT 1 (-1950 3375);
DOT 1 (-1950 3475);
DOT 1 (-1950 3525);
DOT 1 (-1950 3575);
DOT 1 (-1950 3625);
DOT 1 (-1950 3675);
DOT 1 (-1950 3725);
DOT 1 (-1950 3775);
DOT 1 (-1950 3825);
DOT 1 (-1950 3925);
DOT 1 (-1950 3875);
DOT 1 (-1950 3975);
DOT 1 (-1950 4025);
DOT 1 (-1950 4075);
DOT 1 (-3275 4125);
DOT 1 (-3275 4175);
DOT 1 (-3275 4225);
DOT 1 (-3275 4325);
DOT 1 (-3275 4275);
DOT 1 (-3275 4375);
DOT 1 (-3275 4425);
DOT 1 (-3275 4475);
DOT 1 (-3275 4525);
DOT 1 (-3275 4575);
DOT 1 (-3275 4625);
DOT 1 (-3275 4675);
DOT 1 (-3275 4725);
DOT 1 (-3275 4775);
DOT 1 (-3275 4825);
DOT 1 (-3275 4875);
DOT 1 (-3275 4925);
DOT 1 (-3275 4975);
DOT 1 (-3275 5025);
DOT 1 (-3275 5075);
DOT 1 (-3275 5125);
DOT 1 (-3275 5175);
DOT 1 (-3275 5225);
DOT 1 (-3275 5375);
DOT 1 (-3275 5325);
DOT 1 (-3275 5275);
DOT 1 (-3275 5425);
DOT 1 (-3275 5475);
DOT 1 (-3275 5625);
DOT 1 (-3275 5575);
DOT 1 (-3275 5525);
DOT 1 (-3275 5675);
DOT 1 (-3275 5725);
DOT 1 (-3275 5875);
DOT 1 (-3275 5825);
DOT 1 (-3275 5775);
DOT 1 (-3275 5925);
DOT 1 (-3275 5975);
DOT 1 (-3275 6025);
DOT 1 (-3275 6125);
DOT 1 (-3275 6075);
DOT 1 (-3275 6225);
DOT 1 (-3275 6175);
DOT 1 (-3275 6275);
DOT 1 (-3275 6325);
DOT 1 (-1950 4175);
DOT 1 (-1950 4125);
DOT 1 (-1950 4225);
DOT 1 (-1950 4275);
DOT 1 (-1950 4325);
DOT 1 (-1950 4375);
DOT 1 (-1950 4425);
DOT 1 (-1950 4475);
DOT 1 (-1950 4575);
DOT 1 (-1950 4525);
DOT 1 (-1950 4625);
DOT 1 (-1950 4675);
DOT 1 (-1950 4725);
DOT 1 (-1950 4825);
DOT 1 (-1950 4775);
DOT 1 (-1950 4875);
DOT 1 (-1950 4925);
DOT 1 (-1950 4975);
DOT 1 (-1950 5075);
DOT 1 (-1950 5025);
DOT 1 (-1950 5125);
DOT 1 (-1950 5175);
DOT 1 (-1950 5225);
DOT 1 (-1950 5275);
DOT 1 (-1950 5325);
DOT 1 (-1950 5375);
DOT 1 (-1950 5475);
DOT 1 (-1950 5425);
DOT 1 (-1950 5525);
DOT 1 (-1950 5575);
DOT 1 (-1950 5625);
DOT 1 (-1950 5675);
DOT 1 (-1950 5725);
DOT 1 (-1950 5775);
DOT 1 (-1950 5825);
DOT 1 (-1950 5875);
DOT 1 (-1950 5975);
DOT 1 (-1950 5925);
DOT 1 (-1950 6025);
DOT 1 (-1950 6075);
DOT 1 (-1950 6125);
DOT 1 (-1950 6225);
DOT 1 (-1950 6175);
DOT 1 (-1950 6275);
DOT 1 (-1950 6325);
DOT 1 (-1950 6375);
DOT 1 (-1950 525);
DOT 1 (-1950 625);
DOT 1 (-1950 725);
DOT 1 (-1950 825);
DOT 1 (-1950 925);
DOT 1 (-3275 3825);
DOT 1 (-1650 625);
DOT 1 (-1650 725);
DOT 1 (-1650 675);
DOT 1 (-1650 775);
DOT 1 (-1650 825);
DOT 1 (-1650 875);
DOT 1 (-1650 975);
DOT 1 (-1650 925);
DOT 1 (-1650 1025);
DOT 1 (-1650 1075);
DOT 1 (-1650 1125);
DOT 1 (-1650 1175);
DOT 1 (-1650 1225);
DOT 1 (-1650 1275);
DOT 1 (-1650 1375);
DOT 1 (-1650 1325);
DOT 1 (-1650 1425);
DOT 1 (-1650 1475);
DOT 1 (-1650 1525);
DOT 1 (-1650 1625);
DOT 1 (-1650 1575);
DOT 1 (-1650 1675);
DOT 1 (-1650 1725);
DOT 1 (-1650 1775);
DOT 1 (-1650 1875);
DOT 1 (-1650 1825);
DOT 1 (-1650 1925);
DOT 1 (-1650 1975);
DOT 1 (-1650 2025);
DOT 1 (-325 525);
DOT 1 (-325 625);
DOT 1 (-325 575);
DOT 1 (-325 725);
DOT 1 (-325 675);
DOT 1 (-325 775);
DOT 1 (-325 875);
DOT 1 (-325 825);
DOT 1 (-325 925);
DOT 1 (-325 975);
DOT 1 (-325 1025);
DOT 1 (-325 1125);
DOT 1 (-325 1075);
DOT 1 (-325 1275);
DOT 1 (-325 1225);
DOT 1 (-325 1175);
DOT 1 (-325 1375);
DOT 1 (-325 1325);
DOT 1 (-325 1475);
DOT 1 (-325 1525);
DOT 1 (-325 1425);
DOT 1 (-325 1625);
DOT 1 (-325 1575);
DOT 1 (-325 1675);
DOT 1 (-325 1775);
DOT 1 (-325 1725);
DOT 1 (-325 1875);
DOT 1 (-325 1825);
DOT 1 (-325 1925);
DOT 1 (-325 2025);
DOT 1 (-325 1975);
DOT 1 (-1650 2075);
DOT 1 (-1650 2125);
DOT 1 (-1650 2175);
DOT 1 (-1650 2275);
DOT 1 (-1650 2225);
DOT 1 (-1650 2325);
DOT 1 (-1650 2375);
DOT 1 (-1650 2425);
DOT 1 (-1650 2525);
DOT 1 (-1650 2475);
DOT 1 (-1650 2575);
DOT 1 (-1650 2625);
DOT 1 (-1650 2675);
DOT 1 (-1650 2775);
DOT 1 (-1650 2725);
DOT 1 (-1650 2825);
DOT 1 (-1650 2875);
DOT 1 (-1650 2925);
DOT 1 (-1650 3025);
DOT 1 (-1650 2975);
DOT 1 (-1650 3075);
DOT 1 (-1650 3125);
DOT 1 (-1650 3175);
DOT 1 (-1650 3225);
DOT 1 (-1650 3275);
DOT 1 (-1650 3325);
DOT 1 (-1650 3425);
DOT 1 (-1650 3375);
DOT 1 (-1650 3475);
DOT 1 (-1650 3525);
DOT 1 (-1650 3575);
DOT 1 (-1650 3675);
DOT 1 (-1650 3625);
DOT 1 (-1650 3725);
DOT 1 (-1650 3775);
DOT 1 (-1650 3825);
DOT 1 (-1650 3925);
DOT 1 (-1650 3875);
DOT 1 (-1650 3975);
DOT 1 (-1650 4025);
DOT 1 (-1650 4075);
DOT 1 (-325 2175);
DOT 1 (-325 2125);
DOT 1 (-325 2075);
DOT 1 (-325 2275);
DOT 1 (-325 2225);
DOT 1 (-325 2425);
DOT 1 (-325 2375);
DOT 1 (-325 2325);
DOT 1 (-325 2475);
DOT 1 (-325 2525);
DOT 1 (-325 2625);
DOT 1 (-325 2675);
DOT 1 (-325 2575);
DOT 1 (-325 2725);
DOT 1 (-325 2775);
DOT 1 (-325 2825);
DOT 1 (-325 2925);
DOT 1 (-325 2875);
DOT 1 (-325 2975);
DOT 1 (-325 3025);
DOT 1 (-325 3075);
DOT 1 (-325 3175);
DOT 1 (-325 3125);
DOT 1 (-325 3275);
DOT 1 (-325 3325);
DOT 1 (-325 3225);
DOT 1 (-325 3425);
DOT 1 (-325 3375);
DOT 1 (-325 3525);
DOT 1 (-325 3575);
DOT 1 (-325 3475);
DOT 1 (-325 3675);
DOT 1 (-325 3625);
DOT 1 (-325 3725);
DOT 1 (-325 3825);
DOT 1 (-325 3775);
DOT 1 (-325 3925);
DOT 1 (-325 3875);
DOT 1 (-325 3975);
DOT 1 (-325 4075);
DOT 1 (-325 4025);
DOT 1 (-1650 4175);
DOT 1 (-1650 4125);
DOT 1 (-1650 4225);
DOT 1 (-1650 4275);
DOT 1 (-1650 4325);
DOT 1 (-1650 4375);
DOT 1 (-1650 4425);
DOT 1 (-1650 4475);
DOT 1 (-1650 4575);
DOT 1 (-1650 4525);
DOT 1 (-1650 4625);
DOT 1 (-1650 4675);
DOT 1 (-1650 4725);
DOT 1 (-1650 4825);
DOT 1 (-1650 4775);
DOT 1 (-1650 4875);
DOT 1 (-1650 4925);
DOT 1 (-1650 4975);
DOT 1 (-1650 5075);
DOT 1 (-1650 5025);
DOT 1 (-1650 5125);
DOT 1 (-1650 5175);
DOT 1 (-1650 5225);
DOT 1 (-1650 5275);
DOT 1 (-1650 5325);
DOT 1 (-1650 5375);
DOT 1 (-1650 5475);
DOT 1 (-1650 5425);
DOT 1 (-1650 5525);
DOT 1 (-1650 5575);
DOT 1 (-1650 5625);
DOT 1 (-1650 5725);
DOT 1 (-1650 5675);
DOT 1 (-1650 5775);
DOT 1 (-1650 5825);
DOT 1 (-1650 5875);
DOT 1 (-1650 5975);
DOT 1 (-1650 5925);
DOT 1 (-1650 6025);
DOT 1 (-1650 6075);
DOT 1 (-1650 6125);
DOT 1 (-325 4175);
DOT 1 (-325 4125);
DOT 1 (-325 4225);
DOT 1 (-325 4325);
DOT 1 (-325 4275);
DOT 1 (-325 4475);
DOT 1 (-325 4425);
DOT 1 (-325 4375);
DOT 1 (-325 4525);
DOT 1 (-325 4575);
DOT 1 (-325 4675);
DOT 1 (-325 4725);
DOT 1 (-325 4625);
DOT 1 (-325 4775);
DOT 1 (-325 4825);
DOT 1 (-325 4875);
DOT 1 (-325 4975);
DOT 1 (-325 4925);
DOT 1 (-325 5025);
DOT 1 (-325 5075);
DOT 1 (-325 5125);
DOT 1 (-325 5225);
DOT 1 (-325 5175);
DOT 1 (-325 5325);
DOT 1 (-325 5375);
DOT 1 (-325 5275);
DOT 1 (-325 5475);
DOT 1 (-325 5425);
DOT 1 (-325 5575);
DOT 1 (-325 5625);
DOT 1 (-325 5525);
DOT 1 (-325 5725);
DOT 1 (-325 5675);
DOT 1 (-325 5825);
DOT 1 (-325 5875);
DOT 1 (-325 5775);
DOT 1 (-325 5975);
DOT 1 (-325 5925);
DOT 1 (-325 6025);
DOT 1 (-325 6125);
DOT 1 (-325 6075);
DOT 1 (-1650 6225);
DOT 1 (-1650 6175);
DOT 1 (-1650 6275);
DOT 1 (-1650 6325);
DOT 1 (-1650 6375);
DOT 1 (-325 6225);
DOT 1 (-325 6175);
DOT 1 (-325 6275);
DOT 1 (-325 6375);
DOT 1 (-325 6325);
DOT 1 (-1650 575);
DOT 1 (-1650 525);
QUIT
